G04 ================== begin FILE IDENTIFICATION RECORD ==================*
G04 Layout Name:  12433-2a.brd*
G04 Film Name:    DRILL*
G04 File Format:  Gerber RS274X*
G04 File Origin:  Cadence Allegro 16.5-S056*
G04 Origin Date:  Fri Dec 11 16:47:34 2015*
G04 *
G04 Layer:  MANUFACTURING/NCLEGEND-1-4*
G04 Layer:  MANUFACTURING/DRILL SIZE*
G04 Layer:  DRAWING FORMAT/LAYER_PCB_STORY*
G04 Layer:  DRAWING FORMAT/LAYER_DRILL*
G04 Layer:  BOARD GEOMETRY/PANEL_OUTLINE*
G04 *
G04 Offset:    (0.00 0.00)*
G04 Mirror:    No*
G04 Mode:      Positive*
G04 Rotation:  0*
G04 FullContactRelief:  No*
G04 UndefLineWidth:     6.00*
G04 ================== end FILE IDENTIFICATION RECORD ====================*
%FSLAX35Y35*MOIN*%
%IR0*IPPOS*OFA0.00000B0.00000*MIA0B0*SFA1.00000B1.00000*%
%AMMACRO22*
1,1,.006,-.024875,.074625*
20,1,.006,-.024875,.074625,.024875,.074625,0.0*
1,1,.006,.024875,.074625*
20,1,.006,.024875,.074625,.037833,.073491,0.0*
1,1,.006,.037833,.073491*
20,1,.006,.037833,.073491,.050398,.070125,0.0*
1,1,.006,.050398,.070125*
20,1,.006,.050398,.070125,.062187,.064627,0.0*
1,1,.006,.062187,.064627*
20,1,.006,.062187,.064627,.072843,.057166,0.0*
1,1,.006,.072843,.057166*
20,1,.006,.072843,.057166,.082041,.047968,0.0*
1,1,.006,.082041,.047968*
20,1,.006,.082041,.047968,.089502,.037313,0.0*
1,1,.006,.089502,.037313*
20,1,.006,.089502,.037313,.095,.025523,0.0*
1,1,.006,.095,.025523*
20,1,.006,.095,.025523,.098366,.012958,0.0*
1,1,.006,.098366,.012958*
20,1,.006,.098366,.012958,.0995,0.0,0.0*
1,1,.006,.0995,0.0*
20,1,.006,.0995,0.0,.098366,-.012958,0.0*
1,1,.006,.098366,-.012958*
20,1,.006,.098366,-.012958,.095,-.025523,0.0*
1,1,.006,.095,-.025523*
20,1,.006,.095,-.025523,.089502,-.037312,0.0*
1,1,.006,.089502,-.037312*
20,1,.006,.089502,-.037312,.082041,-.047968,0.0*
1,1,.006,.082041,-.047968*
20,1,.006,.082041,-.047968,.072843,-.057166,0.0*
1,1,.006,.072843,-.057166*
20,1,.006,.072843,-.057166,.062188,-.064627,0.0*
1,1,.006,.062188,-.064627*
20,1,.006,.062188,-.064627,.050398,-.070125,0.0*
1,1,.006,.050398,-.070125*
20,1,.006,.050398,-.070125,.037833,-.073491,0.0*
1,1,.006,.037833,-.073491*
20,1,.006,.037833,-.073491,.024875,-.074625,0.0*
1,1,.006,.024875,-.074625*
20,1,.006,.024875,-.074625,-.024875,-.074625,0.0*
1,1,.006,-.024875,-.074625*
20,1,.006,-.024875,-.074625,-.037833,-.073491,0.0*
1,1,.006,-.037833,-.073491*
20,1,.006,-.037833,-.073491,-.050398,-.070125,0.0*
1,1,.006,-.050398,-.070125*
20,1,.006,-.050398,-.070125,-.062187,-.064627,0.0*
1,1,.006,-.062187,-.064627*
20,1,.006,-.062187,-.064627,-.072843,-.057166,0.0*
1,1,.006,-.072843,-.057166*
20,1,.006,-.072843,-.057166,-.082041,-.047968,0.0*
1,1,.006,-.082041,-.047968*
20,1,.006,-.082041,-.047968,-.089502,-.037313,0.0*
1,1,.006,-.089502,-.037313*
20,1,.006,-.089502,-.037313,-.095,-.025523,0.0*
1,1,.006,-.095,-.025523*
20,1,.006,-.095,-.025523,-.098366,-.012958,0.0*
1,1,.006,-.098366,-.012958*
20,1,.006,-.098366,-.012958,-.0995,0.0,0.0*
1,1,.006,-.0995,0.0*
20,1,.006,-.0995,0.0,-.098366,.012958,0.0*
1,1,.006,-.098366,.012958*
20,1,.006,-.098366,.012958,-.095,.025523,0.0*
1,1,.006,-.095,.025523*
20,1,.006,-.095,.025523,-.089502,.037312,0.0*
1,1,.006,-.089502,.037312*
20,1,.006,-.089502,.037312,-.082041,.047968,0.0*
1,1,.006,-.082041,.047968*
20,1,.006,-.082041,.047968,-.072843,.057166,0.0*
1,1,.006,-.072843,.057166*
20,1,.006,-.072843,.057166,-.062188,.064627,0.0*
1,1,.006,-.062188,.064627*
20,1,.006,-.062188,.064627,-.050398,.070125,0.0*
1,1,.006,-.050398,.070125*
20,1,.006,-.050398,.070125,-.037833,.073491,0.0*
1,1,.006,-.037833,.073491*
20,1,.006,-.037833,.073491,-.024875,.074625,0.0*
1,1,.006,-.024875,.074625*
1,1,.006,0.0,-.03731*
20,1,.006,0.0,-.03731,.0087,-.03607,0.0*
1,1,.006,.0087,-.03607*
20,1,.006,.0087,-.03607,.01865,-.03234,0.0*
1,1,.006,.01865,-.03234*
20,1,.006,.01865,-.03234,.02487,-.02612,0.0*
1,1,.006,.02487,-.02612*
20,1,.006,.02487,-.02612,.02736,-.01741,0.0*
1,1,.006,.02736,-.01741*
20,1,.006,.02736,-.01741,.02487,-.00871,0.0*
1,1,.006,.02487,-.00871*
20,1,.006,.02487,-.00871,.01741,-.00124,0.0*
1,1,.006,.01741,-.00124*
20,1,.006,.01741,-.00124,.00622,.00249,0.0*
1,1,.006,.00622,.00249*
20,1,.006,.00622,.00249,-.00622,.00249,0.0*
1,1,.006,-.00622,.00249*
20,1,.006,-.00622,.00249,-.01368,.00497,0.0*
1,1,.006,-.01368,.00497*
20,1,.006,-.01368,.00497,-.0199,.01119,0.0*
1,1,.006,-.0199,.01119*
20,1,.006,-.0199,.01119,-.02239,.0199,0.0*
1,1,.006,-.02239,.0199*
20,1,.006,-.02239,.0199,-.01865,.0286,0.0*
1,1,.006,-.01865,.0286*
20,1,.006,-.01865,.0286,-.00995,.03482,0.0*
1,1,.006,-.00995,.03482*
20,1,.006,-.00995,.03482,0.0,.03731,0.0*
1,1,.006,0.0,.03731*
20,1,.006,0.0,.03731,.00995,.03482,0.0*
1,1,.006,.00995,.03482*
20,1,.006,.00995,.03482,.01865,.0286,0.0*
1,1,.006,.01865,.0286*
20,1,.006,.01865,.0286,.02239,.0199,0.0*
1,1,.006,.02239,.0199*
20,1,.006,.02239,.0199,.0199,.01119,0.0*
1,1,.006,.0199,.01119*
20,1,.006,.0199,.01119,.01368,.00497,0.0*
1,1,.006,.01368,.00497*
20,1,.006,.01368,.00497,.00622,.00249,0.0*
1,1,.006,.00622,.00249*
20,1,.006,.00622,.00249,-.00622,.00249,0.0*
1,1,.006,-.00622,.00249*
20,1,.006,-.00622,.00249,-.01741,-.00124,0.0*
1,1,.006,-.01741,-.00124*
20,1,.006,-.01741,-.00124,-.02487,-.00871,0.0*
1,1,.006,-.02487,-.00871*
20,1,.006,-.02487,-.00871,-.02736,-.01741,0.0*
1,1,.006,-.02736,-.01741*
20,1,.006,-.02736,-.01741,-.02487,-.02612,0.0*
1,1,.006,-.02487,-.02612*
20,1,.006,-.02487,-.02612,-.01865,-.03234,0.0*
1,1,.006,-.01865,-.03234*
20,1,.006,-.01865,-.03234,-.0087,-.03607,0.0*
1,1,.006,-.0087,-.03607*
20,1,.006,-.0087,-.03607,0.0,-.03731,0.0*
1,1,.006,0.0,-.03731*
%
%ADD22MACRO22*%
%AMMACRO20*
1,1,.006,-.037125,.012375*
20,1,.006,-.037125,.012375,-.036561,.018822,0.0*
1,1,.006,-.036561,.018822*
20,1,.006,-.036561,.018822,-.034886,.025072,0.0*
1,1,.006,-.034886,.025072*
20,1,.006,-.034886,.025072,-.032151,.030937,0.0*
1,1,.006,-.032151,.030937*
20,1,.006,-.032151,.030937,-.028439,.036238,0.0*
1,1,.006,-.028439,.036238*
20,1,.006,-.028439,.036238,-.023863,.040814,0.0*
1,1,.006,-.023863,.040814*
20,1,.006,-.023863,.040814,-.018563,.044526,0.0*
1,1,.006,-.018563,.044526*
20,1,.006,-.018563,.044526,-.012697,.047261,0.0*
1,1,.006,-.012697,.047261*
20,1,.006,-.012697,.047261,-.006447,.048936,0.0*
1,1,.006,-.006447,.048936*
20,1,.006,-.006447,.048936,0.0,.0495,0.0*
1,1,.006,0.0,.0495*
20,1,.006,0.0,.0495,.006447,.048936,0.0*
1,1,.006,.006447,.048936*
20,1,.006,.006447,.048936,.012697,.047261,0.0*
1,1,.006,.012697,.047261*
20,1,.006,.012697,.047261,.018562,.044526,0.0*
1,1,.006,.018562,.044526*
20,1,.006,.018562,.044526,.023863,.040814,0.0*
1,1,.006,.023863,.040814*
20,1,.006,.023863,.040814,.028439,.036238,0.0*
1,1,.006,.028439,.036238*
20,1,.006,.028439,.036238,.032151,.030938,0.0*
1,1,.006,.032151,.030938*
20,1,.006,.032151,.030938,.034886,.025072,0.0*
1,1,.006,.034886,.025072*
20,1,.006,.034886,.025072,.036561,.018822,0.0*
1,1,.006,.036561,.018822*
20,1,.006,.036561,.018822,.037125,.012375,0.0*
1,1,.006,.037125,.012375*
20,1,.006,.037125,.012375,.037125,-.012375,0.0*
1,1,.006,.037125,-.012375*
20,1,.006,.037125,-.012375,.036561,-.018822,0.0*
1,1,.006,.036561,-.018822*
20,1,.006,.036561,-.018822,.034886,-.025072,0.0*
1,1,.006,.034886,-.025072*
20,1,.006,.034886,-.025072,.032151,-.030937,0.0*
1,1,.006,.032151,-.030937*
20,1,.006,.032151,-.030937,.028439,-.036238,0.0*
1,1,.006,.028439,-.036238*
20,1,.006,.028439,-.036238,.023863,-.040814,0.0*
1,1,.006,.023863,-.040814*
20,1,.006,.023863,-.040814,.018563,-.044526,0.0*
1,1,.006,.018563,-.044526*
20,1,.006,.018563,-.044526,.012697,-.047261,0.0*
1,1,.006,.012697,-.047261*
20,1,.006,.012697,-.047261,.006447,-.048936,0.0*
1,1,.006,.006447,-.048936*
20,1,.006,.006447,-.048936,0.0,-.0495,0.0*
1,1,.006,0.0,-.0495*
20,1,.006,0.0,-.0495,-.006447,-.048936,0.0*
1,1,.006,-.006447,-.048936*
20,1,.006,-.006447,-.048936,-.012697,-.047261,0.0*
1,1,.006,-.012697,-.047261*
20,1,.006,-.012697,-.047261,-.018562,-.044526,0.0*
1,1,.006,-.018562,-.044526*
20,1,.006,-.018562,-.044526,-.023863,-.040814,0.0*
1,1,.006,-.023863,-.040814*
20,1,.006,-.023863,-.040814,-.028439,-.036238,0.0*
1,1,.006,-.028439,-.036238*
20,1,.006,-.028439,-.036238,-.032151,-.030938,0.0*
1,1,.006,-.032151,-.030938*
20,1,.006,-.032151,-.030938,-.034886,-.025072,0.0*
1,1,.006,-.034886,-.025072*
20,1,.006,-.034886,-.025072,-.036561,-.018822,0.0*
1,1,.006,-.036561,-.018822*
20,1,.006,-.036561,-.018822,-.037125,-.012375,0.0*
1,1,.006,-.037125,-.012375*
20,1,.006,-.037125,-.012375,-.037125,.012375,0.0*
1,1,.006,-.037125,.012375*
1,1,.006,-.01052,-.01423*
20,1,.006,-.01052,-.01423,-.00619,-.01732,0.0*
1,1,.006,-.00619,-.01732*
20,1,.006,-.00619,-.01732,-.00124,-.01856,0.0*
1,1,.006,-.00124,-.01856*
20,1,.006,-.00124,-.01856,.00371,-.01732,0.0*
1,1,.006,.00371,-.01732*
20,1,.006,.00371,-.01732,.00804,-.01361,0.0*
1,1,.006,.00804,-.01361*
20,1,.006,.00804,-.01361,.01114,-.00804,0.0*
1,1,.006,.01114,-.00804*
20,1,.006,.01114,-.00804,.01237,-.00247,0.0*
1,1,.006,.01237,-.00247*
20,1,.006,.01237,-.00247,.01237,.00433,0.0*
1,1,.006,.01237,.00433*
20,1,.006,.01237,.00433,.01114,.0099,0.0*
1,1,.006,.01114,.0099*
20,1,.006,.01114,.0099,.00804,.01485,0.0*
1,1,.006,.00804,.01485*
20,1,.006,.00804,.01485,.00433,.01732,0.0*
1,1,.006,.00433,.01732*
20,1,.006,.00433,.01732,0.0,.01856,0.0*
1,1,.006,0.0,.01856*
20,1,.006,0.0,.01856,-.00495,.01732,0.0*
1,1,.006,-.00495,.01732*
20,1,.006,-.00495,.01732,-.00866,.01485,0.0*
1,1,.006,-.00866,.01485*
20,1,.006,-.00866,.01485,-.01114,.01114,0.0*
1,1,.006,-.01114,.01114*
20,1,.006,-.01114,.01114,-.01237,.00619,0.0*
1,1,.006,-.01237,.00619*
20,1,.006,-.01237,.00619,-.01114,.00186,0.0*
1,1,.006,-.01114,.00186*
20,1,.006,-.01114,.00186,-.00804,-.00247,0.0*
1,1,.006,-.00804,-.00247*
20,1,.006,-.00804,-.00247,-.00433,-.00495,0.0*
1,1,.006,-.00433,-.00495*
20,1,.006,-.00433,-.00495,0.0,-.00557,0.0*
1,1,.006,0.0,-.00557*
20,1,.006,0.0,-.00557,.00495,-.00433,0.0*
1,1,.006,.00495,-.00433*
20,1,.006,.00495,-.00433,.00866,-.00124,0.0*
1,1,.006,.00866,-.00124*
20,1,.006,.00866,-.00124,.01237,.00433,0.0*
1,1,.006,.01237,.00433*
%
%ADD20MACRO20*%
%AMMACRO15*
1,1,.006,.006,0.0*
20,1,.006,.006,0.0,-.006,0.0,0.0*
1,1,.006,-.006,0.0*
1,1,.006,0.0,.006*
20,1,.006,0.0,.006,0.0,-.006,0.0*
1,1,.006,0.0,-.006*
1,1,.006,.003,0.0*
20,1,.006,.003,0.0,.003,.006,0.0*
1,1,.006,.003,.006*
20,1,.006,.003,.006,.0018,.0048,0.0*
1,1,.006,.0018,.0048*
1,1,.006,.0018,0.0*
20,1,.006,.0018,0.0,.0042,0.0,0.0*
1,1,.006,.0042,0.0*
%
%ADD15MACRO15*%
%AMMACRO21*
1,1,.006,.008491,-.0205*
20,1,.006,.008491,-.0205,-.008491,-.0205,0.0*
1,1,.006,-.008491,-.0205*
20,1,.006,-.008491,-.0205,-.0205,-.008491,0.0*
1,1,.006,-.0205,-.008491*
20,1,.006,-.0205,-.008491,-.0205,.008491,0.0*
1,1,.006,-.0205,.008491*
20,1,.006,-.0205,.008491,-.008491,.0205,0.0*
1,1,.006,-.008491,.0205*
20,1,.006,-.008491,.0205,.008491,.0205,0.0*
1,1,.006,.008491,.0205*
20,1,.006,.008491,.0205,.0205,.008491,0.0*
1,1,.006,.0205,.008491*
20,1,.006,.0205,.008491,.0205,-.008491,0.0*
1,1,.006,.0205,-.008491*
20,1,.006,.0205,-.008491,.008491,-.0205,0.0*
1,1,.006,.008491,-.0205*
1,1,.006,-.00752,-.00718*
20,1,.006,-.00752,-.00718,-.00547,-.00888,0.0*
1,1,.006,-.00547,-.00888*
20,1,.006,-.00547,-.00888,-.00308,-.00991,0.0*
1,1,.006,-.00308,-.00991*
20,1,.006,-.00308,-.00991,0.0,-.01025,0.0*
1,1,.006,0.0,-.01025*
20,1,.006,0.0,-.01025,.00308,-.00957,0.0*
1,1,.006,.00308,-.00957*
20,1,.006,.00308,-.00957,.00547,-.0082,0.0*
1,1,.006,.00547,-.0082*
20,1,.006,.00547,-.0082,.00718,-.00581,0.0*
1,1,.006,.00718,-.00581*
20,1,.006,.00718,-.00581,.00752,-.00308,0.0*
1,1,.006,.00752,-.00308*
20,1,.006,.00752,-.00308,.00683,-.00034,0.0*
1,1,.006,.00683,-.00034*
20,1,.006,.00683,-.00034,.00512,.00137,0.0*
1,1,.006,.00512,.00137*
20,1,.006,.00512,.00137,.00273,.00273,0.0*
1,1,.006,.00273,.00273*
20,1,.006,.00273,.00273,.00034,.00307,0.0*
1,1,.006,.00034,.00307*
20,1,.006,.00034,.00307,-.00205,.00273,0.0*
1,1,.006,-.00205,.00273*
20,1,.006,-.00205,.00273,-.00512,.00137,0.0*
1,1,.006,-.00512,.00137*
20,1,.006,-.00512,.00137,-.0041,.01025,0.0*
1,1,.006,-.0041,.01025*
20,1,.006,-.0041,.01025,.00512,.01025,0.0*
1,1,.006,.00512,.01025*
%
%ADD21MACRO21*%
%AMMACRO12*
1,1,.006,.008,.008*
20,1,.006,.008,.008,.008,-.008,0.0*
1,1,.006,.008,-.008*
20,1,.006,.008,-.008,-.008,-.008,0.0*
1,1,.006,-.008,-.008*
20,1,.006,-.008,-.008,-.008,.008,0.0*
1,1,.006,-.008,.008*
20,1,.006,-.008,.008,.008,.008,0.0*
1,1,.006,.008,.008*
1,1,.006,-.00253,.00267*
20,1,.006,-.00253,.00267,-.00173,.00347,0.0*
1,1,.006,-.00173,.00347*
20,1,.006,-.00173,.00347,-.0008,.00387,0.0*
1,1,.006,-.0008,.00387*
20,1,.006,-.0008,.00387,.00027,.004,0.0*
1,1,.006,.00027,.004*
20,1,.006,.00027,.004,.0016,.00373,0.0*
1,1,.006,.0016,.00373*
20,1,.006,.0016,.00373,.00253,.00307,0.0*
1,1,.006,.00253,.00307*
20,1,.006,.00253,.00307,.0028,.00227,0.0*
1,1,.006,.0028,.00227*
20,1,.006,.0028,.00227,.00267,.00147,0.0*
1,1,.006,.00267,.00147*
20,1,.006,.00267,.00147,.00213,.0008,0.0*
1,1,.006,.00213,.0008*
20,1,.006,.00213,.0008,-.00053,-.00053,0.0*
1,1,.006,-.00053,-.00053*
20,1,.006,-.00053,-.00053,-.00173,-.00147,0.0*
1,1,.006,-.00173,-.00147*
20,1,.006,-.00173,-.00147,-.00253,-.0028,0.0*
1,1,.006,-.00253,-.0028*
20,1,.006,-.00253,-.0028,-.0028,-.004,0.0*
1,1,.006,-.0028,-.004*
20,1,.006,-.0028,-.004,.0028,-.004,0.0*
1,1,.006,.0028,-.004*
%
%ADD12MACRO12*%
%AMMACRO10*
1,1,.006,-.05834,-.07*
20,1,.006,-.05834,-.07,0.0,.07,0.0*
1,1,.006,0.0,.07*
20,1,.006,0.0,.07,.05834,-.07,0.0*
1,1,.006,.05834,-.07*
1,1,.006,.03733,-.021*
20,1,.006,.03733,-.021,-.03734,-.021,0.0*
1,1,.006,-.03734,-.021*
%
%ADD10MACRO10*%
%AMMACRO11*
1,1,.006,.01893,.00473*
20,1,.006,.01893,.00473,.0284,.01183,0.0*
1,1,.006,.0284,.01183*
20,1,.006,.0284,.01183,.0355,.02366,0.0*
1,1,.006,.0355,.02366*
20,1,.006,.0355,.02366,.04024,.04024,0.0*
1,1,.006,.04024,.04024*
20,1,.006,.04024,.04024,.0355,.05443,0.0*
1,1,.006,.0355,.05443*
20,1,.006,.0355,.05443,.02603,.0639,0.0*
1,1,.006,.02603,.0639*
20,1,.006,.02603,.0639,.00947,.071,0.0*
1,1,.006,.00947,.071*
20,1,.006,.00947,.071,-.05443,.071,0.0*
1,1,.006,-.05443,.071*
20,1,.006,-.05443,.071,-.05443,-.071,0.0*
1,1,.006,-.05443,-.071*
20,1,.006,-.05443,-.071,.02367,-.071,0.0*
1,1,.006,.02367,-.071*
20,1,.006,.02367,-.071,.04024,-.06154,0.0*
1,1,.006,.04024,-.06154*
20,1,.006,.04024,-.06154,.0497,-.04733,0.0*
1,1,.006,.0497,-.04733*
20,1,.006,.0497,-.04733,.05443,-.03077,0.0*
1,1,.006,.05443,-.03077*
20,1,.006,.05443,-.03077,.0497,-.0142,0.0*
1,1,.006,.0497,-.0142*
20,1,.006,.0497,-.0142,.0355,0.0,0.0*
1,1,.006,.0355,0.0*
20,1,.006,.0355,0.0,.01893,.00473,0.0*
1,1,.006,.01893,.00473*
20,1,.006,.01893,.00473,-.05443,.00473,0.0*
1,1,.006,-.05443,.00473*
%
%ADD11MACRO11*%
%AMMACRO18*
1,1,.006,.0575,.043125*
20,1,.006,.0575,.043125,.0575,-.043125,0.0*
1,1,.006,.0575,-.043125*
20,1,.006,.0575,-.043125,-.0575,-.043125,0.0*
1,1,.006,-.0575,-.043125*
20,1,.006,-.0575,-.043125,-.0575,.043125,0.0*
1,1,.006,-.0575,.043125*
20,1,.006,-.0575,.043125,.0575,.043125,0.0*
1,1,.006,.0575,.043125*
1,1,.006,-.02156,-.02156*
20,1,.006,-.02156,-.02156,-.02156,.02156,0.0*
1,1,.006,-.02156,.02156*
20,1,.006,-.02156,.02156,-.03018,.01294,0.0*
1,1,.006,-.03018,.01294*
1,1,.006,-.03018,-.02156*
20,1,.006,-.03018,-.02156,-.01294,-.02156,0.0*
1,1,.006,-.01294,-.02156*
1,1,.006,.02157,.02156*
20,1,.006,.02157,.02156,.01582,.02012,0.0*
1,1,.006,.01582,.02012*
20,1,.006,.01582,.02012,.01151,.01653,0.0*
1,1,.006,.01151,.01653*
20,1,.006,.01151,.01653,.00863,.01222,0.0*
1,1,.006,.00863,.01222*
20,1,.006,.00863,.01222,.00648,.00647,0.0*
1,1,.006,.00648,.00647*
20,1,.006,.00648,.00647,.00576,0.0,0.0*
1,1,.006,.00576,0.0*
20,1,.006,.00576,0.0,.00648,-.00647,0.0*
1,1,.006,.00648,-.00647*
20,1,.006,.00648,-.00647,.00863,-.01222,0.0*
1,1,.006,.00863,-.01222*
20,1,.006,.00863,-.01222,.01151,-.01653,0.0*
1,1,.006,.01151,-.01653*
20,1,.006,.01151,-.01653,.01582,-.02012,0.0*
1,1,.006,.01582,-.02012*
20,1,.006,.01582,-.02012,.02157,-.02156,0.0*
1,1,.006,.02157,-.02156*
20,1,.006,.02157,-.02156,.02732,-.02012,0.0*
1,1,.006,.02732,-.02012*
20,1,.006,.02732,-.02012,.03163,-.01653,0.0*
1,1,.006,.03163,-.01653*
20,1,.006,.03163,-.01653,.03451,-.01222,0.0*
1,1,.006,.03451,-.01222*
20,1,.006,.03451,-.01222,.03666,-.00647,0.0*
1,1,.006,.03666,-.00647*
20,1,.006,.03666,-.00647,.03738,0.0,0.0*
1,1,.006,.03738,0.0*
20,1,.006,.03738,0.0,.03666,.00647,0.0*
1,1,.006,.03666,.00647*
20,1,.006,.03666,.00647,.03451,.01222,0.0*
1,1,.006,.03451,.01222*
20,1,.006,.03451,.01222,.03163,.01653,0.0*
1,1,.006,.03163,.01653*
20,1,.006,.03163,.01653,.02732,.02012,0.0*
1,1,.006,.02732,.02012*
20,1,.006,.02732,.02012,.02157,.02156,0.0*
1,1,.006,.02157,.02156*
%
%ADD18MACRO18*%
%AMMACRO17*
1,1,.006,.069,0.0*
20,1,.006,.069,0.0,0.0,-.069,0.0*
1,1,.006,0.0,-.069*
20,1,.006,0.0,-.069,-.069,0.0,0.0*
1,1,.006,-.069,0.0*
20,1,.006,-.069,0.0,0.0,.069,0.0*
1,1,.006,0.0,.069*
20,1,.006,0.0,.069,.069,0.0,0.0*
1,1,.006,.069,0.0*
1,1,.006,-.02185,-.00575*
20,1,.006,-.02185,-.00575,-.0138,.0023,0.0*
1,1,.006,-.0138,.0023*
20,1,.006,-.0138,.0023,-.0069,.0069,0.0*
1,1,.006,-.0069,.0069*
20,1,.006,-.0069,.0069,.0023,.0092,0.0*
1,1,.006,.0023,.0092*
20,1,.006,.0023,.0092,.01035,.0069,0.0*
1,1,.006,.01035,.0069*
20,1,.006,.01035,.0069,.0161,.0023,0.0*
1,1,.006,.0161,.0023*
20,1,.006,.0161,.0023,.0207,-.0046,0.0*
1,1,.006,.0207,-.0046*
20,1,.006,.0207,-.0046,.02185,-.01265,0.0*
1,1,.006,.02185,-.01265*
20,1,.006,.02185,-.01265,.0207,-.01955,0.0*
1,1,.006,.0207,-.01955*
20,1,.006,.0207,-.01955,.0161,-.02645,0.0*
1,1,.006,.0161,-.02645*
20,1,.006,.0161,-.02645,.0092,-.0322,0.0*
1,1,.006,.0092,-.0322*
20,1,.006,.0092,-.0322,.00115,-.0345,0.0*
1,1,.006,.00115,-.0345*
20,1,.006,.00115,-.0345,-.00805,-.0322,0.0*
1,1,.006,-.00805,-.0322*
20,1,.006,-.00805,-.0322,-.0161,-.0253,0.0*
1,1,.006,-.0161,-.0253*
20,1,.006,-.0161,-.0253,-.0207,-.01495,0.0*
1,1,.006,-.0207,-.01495*
20,1,.006,-.0207,-.01495,-.02185,-.00345,0.0*
1,1,.006,-.02185,-.00345*
20,1,.006,-.02185,-.00345,-.01955,.0115,0.0*
1,1,.006,-.01955,.0115*
20,1,.006,-.01955,.0115,-.0161,.01955,0.0*
1,1,.006,-.0161,.01955*
20,1,.006,-.0161,.01955,-.01035,.0276,0.0*
1,1,.006,-.01035,.0276*
20,1,.006,-.01035,.0276,-.0023,.03335,0.0*
1,1,.006,-.0023,.03335*
20,1,.006,-.0023,.03335,.00575,.0345,0.0*
1,1,.006,.00575,.0345*
20,1,.006,.00575,.0345,.0138,.0322,0.0*
1,1,.006,.0138,.0322*
20,1,.006,.0138,.0322,.01955,.02645,0.0*
1,1,.006,.01955,.02645*
%
%ADD17MACRO17*%
%AMMACRO19*
1,1,.006,.063,0.0*
20,1,.006,.063,0.0,.062043,-.01094,0.0*
1,1,.006,.062043,-.01094*
20,1,.006,.062043,-.01094,.059201,-.021547,0.0*
1,1,.006,.059201,-.021547*
20,1,.006,.059201,-.021547,.05456,-.0315,0.0*
1,1,.006,.05456,-.0315*
20,1,.006,.05456,-.0315,.048261,-.040496,0.0*
1,1,.006,.048261,-.040496*
20,1,.006,.048261,-.040496,.040496,-.048261,0.0*
1,1,.006,.040496,-.048261*
20,1,.006,.040496,-.048261,.0315,-.05456,0.0*
1,1,.006,.0315,-.05456*
20,1,.006,.0315,-.05456,.021547,-.059201,0.0*
1,1,.006,.021547,-.059201*
20,1,.006,.021547,-.059201,.01094,-.062043,0.0*
1,1,.006,.01094,-.062043*
20,1,.006,.01094,-.062043,0.0,-.063,0.0*
1,1,.006,0.0,-.063*
20,1,.006,0.0,-.063,-.01094,-.062043,0.0*
1,1,.006,-.01094,-.062043*
20,1,.006,-.01094,-.062043,-.021547,-.059201,0.0*
1,1,.006,-.021547,-.059201*
20,1,.006,-.021547,-.059201,-.0315,-.05456,0.0*
1,1,.006,-.0315,-.05456*
20,1,.006,-.0315,-.05456,-.040496,-.048261,0.0*
1,1,.006,-.040496,-.048261*
20,1,.006,-.040496,-.048261,-.048261,-.040496,0.0*
1,1,.006,-.048261,-.040496*
20,1,.006,-.048261,-.040496,-.05456,-.0315,0.0*
1,1,.006,-.05456,-.0315*
20,1,.006,-.05456,-.0315,-.059201,-.021547,0.0*
1,1,.006,-.059201,-.021547*
20,1,.006,-.059201,-.021547,-.062043,-.01094,0.0*
1,1,.006,-.062043,-.01094*
20,1,.006,-.062043,-.01094,-.063,0.0,0.0*
1,1,.006,-.063,0.0*
20,1,.006,-.063,0.0,-.062043,.01094,0.0*
1,1,.006,-.062043,.01094*
20,1,.006,-.062043,.01094,-.059201,.021547,0.0*
1,1,.006,-.059201,.021547*
20,1,.006,-.059201,.021547,-.05456,.0315,0.0*
1,1,.006,-.05456,.0315*
20,1,.006,-.05456,.0315,-.048261,.040496,0.0*
1,1,.006,-.048261,.040496*
20,1,.006,-.048261,.040496,-.040496,.048261,0.0*
1,1,.006,-.040496,.048261*
20,1,.006,-.040496,.048261,-.0315,.05456,0.0*
1,1,.006,-.0315,.05456*
20,1,.006,-.0315,.05456,-.021547,.059201,0.0*
1,1,.006,-.021547,.059201*
20,1,.006,-.021547,.059201,-.01094,.062043,0.0*
1,1,.006,-.01094,.062043*
20,1,.006,-.01094,.062043,0.0,.063,0.0*
1,1,.006,0.0,.063*
20,1,.006,0.0,.063,.01094,.062043,0.0*
1,1,.006,.01094,.062043*
20,1,.006,.01094,.062043,.021547,.059201,0.0*
1,1,.006,.021547,.059201*
20,1,.006,.021547,.059201,.0315,.05456,0.0*
1,1,.006,.0315,.05456*
20,1,.006,.0315,.05456,.040496,.048261,0.0*
1,1,.006,.040496,.048261*
20,1,.006,.040496,.048261,.048261,.040496,0.0*
1,1,.006,.048261,.040496*
20,1,.006,.048261,.040496,.05456,.0315,0.0*
1,1,.006,.05456,.0315*
20,1,.006,.05456,.0315,.059201,.021547,0.0*
1,1,.006,.059201,.021547*
20,1,.006,.059201,.021547,.062043,.01094,0.0*
1,1,.006,.062043,.01094*
20,1,.006,.062043,.01094,.063,0.0,0.0*
1,1,.006,.063,0.0*
1,1,.006,-.0315,-.0315*
20,1,.006,-.0315,-.0315,-.0315,.0315,0.0*
1,1,.006,-.0315,.0315*
20,1,.006,-.0315,.0315,-.0441,.0189,0.0*
1,1,.006,-.0441,.0189*
1,1,.006,-.0441,-.0315*
20,1,.006,-.0441,-.0315,-.0189,-.0315,0.0*
1,1,.006,-.0189,-.0315*
1,1,.006,.03151,-.0315*
20,1,.006,.03151,-.0315,.03151,.0315,0.0*
1,1,.006,.03151,.0315*
20,1,.006,.03151,.0315,.01891,.0189,0.0*
1,1,.006,.01891,.0189*
1,1,.006,.01891,-.0315*
20,1,.006,.01891,-.0315,.04411,-.0315,0.0*
1,1,.006,.04411,-.0315*
%
%ADD19MACRO19*%
%AMMACRO13*
1,1,.006,0.0,.02*
20,1,.006,0.0,.02,-.017321,.01,0.0*
1,1,.006,-.017321,.01*
20,1,.006,-.017321,.01,-.017321,-.01,0.0*
1,1,.006,-.017321,-.01*
20,1,.006,-.017321,-.01,0.0,-.02,0.0*
1,1,.006,0.0,-.02*
20,1,.006,0.0,-.02,.017321,-.01,0.0*
1,1,.006,.017321,-.01*
20,1,.006,.017321,-.01,.017321,.01,0.0*
1,1,.006,.017321,.01*
20,1,.006,.017321,.01,0.0,.02,0.0*
1,1,.006,0.0,.02*
1,1,.006,.004,-.01*
20,1,.006,.004,-.01,.004,.01,0.0*
1,1,.006,.004,.01*
20,1,.006,.004,.01,-.00833,-.00433,0.0*
1,1,.006,-.00833,-.00433*
20,1,.006,-.00833,-.00433,.00833,-.00433,0.0*
1,1,.006,.00833,-.00433*
%
%ADD13MACRO13*%
%AMMACRO16*
1,1,.006,.0175,0.0*
20,1,.006,.0175,0.0,.00875,.015155,0.0*
1,1,.006,.00875,.015155*
20,1,.006,.00875,.015155,-.00875,.015155,0.0*
1,1,.006,-.00875,.015155*
20,1,.006,-.00875,.015155,-.0175,0.0,0.0*
1,1,.006,-.0175,0.0*
20,1,.006,-.0175,0.0,-.00875,-.015155,0.0*
1,1,.006,-.00875,-.015155*
20,1,.006,-.00875,-.015155,.00875,-.015155,0.0*
1,1,.006,.00875,-.015155*
20,1,.006,.00875,-.015155,.0175,0.0,0.0*
1,1,.006,.0175,0.0*
1,1,.006,-.00642,-.00525*
20,1,.006,-.00642,-.00525,-.00467,-.00729,0.0*
1,1,.006,-.00467,-.00729*
20,1,.006,-.00467,-.00729,-.00233,-.00846,0.0*
1,1,.006,-.00233,-.00846*
20,1,.006,-.00233,-.00846,.00029,-.00875,0.0*
1,1,.006,.00029,-.00875*
20,1,.006,.00029,-.00875,.00263,-.00846,0.0*
1,1,.006,.00263,-.00846*
20,1,.006,.00263,-.00846,.00496,-.007,0.0*
1,1,.006,.00496,-.007*
20,1,.006,.00496,-.007,.00642,-.00525,0.0*
1,1,.006,.00642,-.00525*
20,1,.006,.00642,-.00525,.00671,-.0035,0.0*
1,1,.006,.00671,-.0035*
20,1,.006,.00671,-.0035,.00613,-.00146,0.0*
1,1,.006,.00613,-.00146*
20,1,.006,.00613,-.00146,.00408,0.0,0.0*
1,1,.006,.00408,0.0*
20,1,.006,.00408,0.0,.00204,.00058,0.0*
1,1,.006,.00204,.00058*
20,1,.006,.00204,.00058,-.00058,.00058,0.0*
1,1,.006,-.00058,.00058*
1,1,.006,.00204,.00058*
20,1,.006,.00204,.00058,.00379,.00146,0.0*
1,1,.006,.00379,.00146*
20,1,.006,.00379,.00146,.00525,.00292,0.0*
1,1,.006,.00525,.00292*
20,1,.006,.00525,.00292,.00583,.00467,0.0*
1,1,.006,.00583,.00467*
20,1,.006,.00583,.00467,.00525,.00642,0.0*
1,1,.006,.00525,.00642*
20,1,.006,.00525,.00642,.00379,.00787,0.0*
1,1,.006,.00379,.00787*
20,1,.006,.00379,.00787,.00117,.00875,0.0*
1,1,.006,.00117,.00875*
20,1,.006,.00117,.00875,-.00146,.00846,0.0*
1,1,.006,-.00146,.00846*
20,1,.006,-.00146,.00846,-.00408,.00729,0.0*
1,1,.006,-.00408,.00729*
%
%ADD16MACRO16*%
%AMMACRO14*
1,1,.006,0.0,.079*
20,1,.006,0.0,.079,.079,-.079,0.0*
1,1,.006,.079,-.079*
20,1,.006,.079,-.079,-.079,-.079,0.0*
1,1,.006,-.079,-.079*
20,1,.006,-.079,-.079,0.0,.079,0.0*
1,1,.006,0.0,.079*
1,1,.006,-.00263,-.0395*
20,1,.006,-.00263,-.0395,0.0,-.02238,0.0*
1,1,.006,0.0,-.02238*
20,1,.006,0.0,-.02238,.00395,-.0079,0.0*
1,1,.006,.00395,-.0079*
20,1,.006,.00395,-.0079,.00922,.00527,0.0*
1,1,.006,.00922,.00527*
20,1,.006,.00922,.00527,.0158,.01975,0.0*
1,1,.006,.0158,.01975*
20,1,.006,.0158,.01975,.02633,.0395,0.0*
1,1,.006,.02633,.0395*
20,1,.006,.02633,.0395,-.02633,.0395,0.0*
1,1,.006,-.02633,.0395*
%
%ADD14MACRO14*%
%ADD23C,.02*%
%ADD24C,.006*%
G75*
%LPD*%
G75*
G54D10*
X-222440Y19685D03*
Y1948818D03*
X643700Y19685D03*
Y1948818D03*
X822950Y97150D03*
G54D11*
X29921Y24803D03*
Y111417D03*
Y458031D03*
Y544646D03*
Y717874D03*
Y804488D03*
X30000Y1164000D03*
X29921Y1250630D03*
Y1423858D03*
Y1510472D03*
Y1857086D03*
Y1943701D03*
X822950Y69050D03*
G54D20*
X80709Y139409D03*
Y309409D03*
X149606Y139409D03*
Y309409D03*
X822950Y181450D03*
G54D12*
X8594Y6500D03*
X31500Y5500D03*
X20000Y6000D03*
X17000Y36500D03*
X32000Y40000D03*
X5594Y87000D03*
Y53500D03*
X29500Y53000D03*
X26000Y87000D03*
X30800Y130300D03*
X4594Y120500D03*
X34400Y95300D03*
X14000Y141000D03*
X23500Y124000D03*
X15000Y131500D03*
X14500Y100500D03*
Y112500D03*
X4500Y105500D03*
X5000Y137500D03*
X22500Y190000D03*
X29700Y191400D03*
X5594Y153500D03*
X4594Y187500D03*
X16500Y175000D03*
X27000Y182000D03*
X14000Y184000D03*
X4500Y170500D03*
X21500Y241500D03*
X4594Y234000D03*
X24000Y212000D03*
X29000Y200500D03*
X13000Y244000D03*
X13500Y230500D03*
X13000Y212500D03*
X5000Y221000D03*
X12500Y197500D03*
X4500Y202500D03*
X28050Y256950D03*
X5094Y278000D03*
X6094Y257000D03*
X13500Y279000D03*
Y295000D03*
X5500Y295500D03*
X12500Y266500D03*
X5500Y269500D03*
X5000Y247500D03*
X19721Y267203D03*
X5594Y312000D03*
X5304Y342500D03*
X4900Y328000D03*
X13500Y303500D03*
X13000Y321000D03*
X4594Y396500D03*
X6500Y375000D03*
X27000Y371000D03*
X4800Y356200D03*
X23700Y363900D03*
X29500Y364500D03*
X27000Y377500D03*
Y384000D03*
Y389500D03*
X4594Y421000D03*
X5304Y444500D03*
Y440500D03*
X5000Y408500D03*
X5304Y434500D03*
X26500Y440000D03*
X26000Y432500D03*
X23800Y410700D03*
X5094Y469500D03*
X5000Y495000D03*
X4700Y458200D03*
X5000Y486500D03*
X5094Y600000D03*
X34100Y566600D03*
X13510Y597990D03*
X14000Y614000D03*
X4594Y625000D03*
X18000Y608000D03*
X6000Y612000D03*
Y646000D03*
X26000Y656500D03*
X5594Y688500D03*
X5304Y661000D03*
X14000Y659000D03*
X23000Y677500D03*
X32000Y666000D03*
X28000Y706000D03*
X8000Y678000D03*
X31000Y700500D03*
X20000Y696000D03*
X6000Y698000D03*
Y706500D03*
X31000Y747000D03*
X22000Y746000D03*
X24000Y756000D03*
X27000Y750000D03*
X26000Y732000D03*
X18000Y724000D03*
Y732500D03*
Y712000D03*
X6000Y722000D03*
Y730500D03*
X5594Y778000D03*
X6500Y799000D03*
X9500Y804000D03*
X30000Y782000D03*
X16100Y794600D03*
X5594Y844500D03*
X6094Y819500D03*
X30500D03*
X10000Y811500D03*
X24000Y846000D03*
X24500Y853500D03*
X16000Y828000D03*
Y814000D03*
Y856000D03*
Y842000D03*
X32000Y858000D03*
Y844000D03*
X4500Y833500D03*
Y857500D03*
X26053Y828247D03*
X5094Y897500D03*
X5594Y869000D03*
X16000Y906000D03*
X32000Y886000D03*
Y872000D03*
X18000Y884000D03*
Y870000D03*
X5000Y883500D03*
X18500Y896500D03*
X23053Y861247D03*
X5304Y926000D03*
X4594Y954000D03*
X18000Y934000D03*
Y920000D03*
X16000Y962000D03*
Y948000D03*
X4500Y913000D03*
Y941500D03*
X34000Y944000D03*
Y934500D03*
X33500Y962500D03*
Y953000D03*
X26053Y938247D03*
X4594Y1013500D03*
X5594Y984500D03*
X28000Y992000D03*
X26000Y1010000D03*
X16000Y990000D03*
Y976000D03*
Y1014000D03*
Y1000000D03*
X4500Y970000D03*
Y997000D03*
X34000Y984000D03*
Y974500D03*
Y1008000D03*
X25053Y971247D03*
X31600Y1024300D03*
X4594Y1041500D03*
X6000Y1058000D03*
X33600Y1029900D03*
X16000Y1046000D03*
Y1032000D03*
X14000Y1060000D03*
X4500Y1029500D03*
X34000Y1017500D03*
X27553Y1029247D03*
X5094Y1074500D03*
X32000Y1114000D03*
X34000Y1102000D03*
Y1072000D03*
X28000D03*
X14000Y1074000D03*
Y1100000D03*
Y1086000D03*
X16000Y1110000D03*
X6000Y1096000D03*
X26100Y1088600D03*
X27218Y1097000D03*
X33550Y1080100D03*
X34000Y1144000D03*
X16000Y1124000D03*
Y1148000D03*
Y1134000D03*
Y1162000D03*
X6000Y1138000D03*
Y1118000D03*
Y1152000D03*
X26600Y1132400D03*
X24553Y1153247D03*
X5304Y1208000D03*
X4594Y1169500D03*
X24000Y1180000D03*
X16000Y1176000D03*
X5094Y1268500D03*
X8500Y1237000D03*
X30000Y1240000D03*
X16000Y1262000D03*
Y1244000D03*
X28000Y1266000D03*
X6000Y1252000D03*
X22000Y1232000D03*
X31500Y1222000D03*
X6500Y1302000D03*
X17700Y1283000D03*
X34000Y1312000D03*
X6000Y1318000D03*
X12000Y1274000D03*
Y1294000D03*
X28000Y1286000D03*
Y1300000D03*
Y1320000D03*
X19800Y1315400D03*
X13500Y1365000D03*
X8000Y1368000D03*
X30800Y1403900D03*
X31500Y1397500D03*
X5304Y1409400D03*
X4594Y1382000D03*
X7500Y1376500D03*
X32000Y1391500D03*
X4800Y1460700D03*
X4594Y1435500D03*
X34000Y1465900D03*
X5304Y1504100D03*
Y1522100D03*
X4600Y1484800D03*
X34000Y1477600D03*
X29500Y1495800D03*
X5304Y1576200D03*
Y1540500D03*
X26600Y1570100D03*
X26900Y1547900D03*
Y1559100D03*
X4594Y1607500D03*
X33100Y1587400D03*
X26700Y1579800D03*
X7500Y1640200D03*
X5304Y1659000D03*
X4700Y1676100D03*
X4594Y1632000D03*
X29000Y1671000D03*
X19250Y1663100D03*
X13900Y1706200D03*
X5304Y1723500D03*
X4900Y1708000D03*
X13100Y1728900D03*
X4594Y1691000D03*
X30000Y1731000D03*
X4594Y1775000D03*
Y1751000D03*
X12600Y1753800D03*
X13100Y1742600D03*
X12900Y1765200D03*
X14500Y1832500D03*
X12600Y1792800D03*
X12500Y1782500D03*
X4594Y1878500D03*
X14500Y1863500D03*
X5000Y1864100D03*
X18600Y1871400D03*
X4594Y1850000D03*
X15000Y1854900D03*
X27500Y1883500D03*
X14500Y1842000D03*
X28000Y1876500D03*
X29000Y1841000D03*
X13100Y1933900D03*
X24800Y1926500D03*
X5094Y1921000D03*
X4594Y1902000D03*
X35000Y1933500D03*
X35300Y1925300D03*
X34500Y1963200D03*
X16100Y1950700D03*
X5094Y1944500D03*
X15500Y1942500D03*
X4500Y1936000D03*
X6500Y1962000D03*
X25000Y1962500D03*
X12500Y1959000D03*
X63594Y7000D03*
Y25500D03*
X40594Y6000D03*
X49000Y18500D03*
X43000Y27000D03*
X64500Y40000D03*
X64000Y17000D03*
X53000Y5000D03*
X51500Y53000D03*
X74000Y45000D03*
X85000D03*
X63098Y119103D03*
X52000Y115600D03*
X62598Y141103D03*
X51700Y131700D03*
X71000Y131859D03*
X37000Y124000D03*
X51900Y145700D03*
X86000Y152000D03*
X69000Y153000D03*
X73500Y146000D03*
X60800Y147700D03*
X86000Y296000D03*
X68000D03*
X76000D03*
X68000Y286000D03*
Y320000D03*
Y312000D03*
Y304000D03*
X74000Y390000D03*
X66000D03*
X58000D03*
X74000Y400000D03*
X66000D03*
X58000D03*
X64000Y446500D03*
Y451000D03*
X74000Y408000D03*
X66000D03*
Y418000D03*
X74000D03*
X73700Y423000D03*
X66000Y426000D03*
X58000D03*
Y408000D03*
Y417500D03*
X84500Y433000D03*
X58100Y431900D03*
X63096Y434540D03*
X68500Y434300D03*
X81000Y410500D03*
X86400D03*
X78200Y501000D03*
X82000Y483600D03*
X46000Y490500D03*
X71900Y501000D03*
X50100Y493000D03*
X42500D03*
X78200Y481700D03*
X63300Y464400D03*
X64000Y455500D03*
Y460000D03*
X62500Y472900D03*
X62600Y468500D03*
X62500Y477000D03*
X78500Y506700D03*
X71800Y506900D03*
X85000Y506400D03*
X84500Y514400D03*
X72100Y521800D03*
X79400D03*
X72000Y514800D03*
X78000D03*
X51700Y522500D03*
X74942Y530983D03*
X72500Y595900D03*
X56800Y576950D03*
X36000Y554000D03*
X79122Y565700D03*
X79458Y578758D03*
X69800Y574200D03*
X80900Y668400D03*
X86443Y662853D03*
X84504Y666353D03*
X56710Y681069D03*
X39096Y674917D03*
X43281Y674991D03*
X40000Y659000D03*
X71800Y701300D03*
X69100Y698006D03*
X74100Y669398D03*
X50000Y712500D03*
Y749000D03*
X40000Y746500D03*
X36000Y730000D03*
X46000Y726000D03*
X82000Y806500D03*
X44000Y782000D03*
X42000Y802000D03*
Y788000D03*
X47600Y796800D03*
X79000Y857000D03*
X81500Y837500D03*
X82500Y814000D03*
X48000Y816000D03*
X38000Y834000D03*
Y820000D03*
X46000Y848000D03*
Y834000D03*
X78300Y832600D03*
X77600Y849100D03*
X87000Y839500D03*
X48100Y853400D03*
X45600Y827500D03*
X37500Y912000D03*
Y907500D03*
X77000Y871500D03*
X62500Y862000D03*
X61500Y876500D03*
X78000Y878500D03*
X77500Y907000D03*
X85500Y903000D03*
X78300Y893900D03*
X77000Y863000D03*
X83400Y878600D03*
X47000Y877600D03*
X40900Y901500D03*
X41000Y931899D03*
X86500Y932000D03*
X61500Y938500D03*
X81500Y940000D03*
X75500Y936500D03*
X69500Y939000D03*
X55500Y955500D03*
X56500Y940000D03*
X62500Y924500D03*
X70000Y914500D03*
Y925500D03*
X76500Y927000D03*
X85500Y915000D03*
X77500Y917000D03*
X64000Y980500D03*
X87000Y997500D03*
X55500Y968000D03*
X76400Y999100D03*
X37700Y991600D03*
X87000Y1064000D03*
X39300Y1105800D03*
X83500Y1072000D03*
Y1067000D03*
Y1076500D03*
X67302Y1133490D03*
X78292Y1148041D03*
X64500Y1165700D03*
X79044Y1144112D03*
X66000Y1149500D03*
X37500Y1118900D03*
X74000Y1132000D03*
X40000Y1136000D03*
Y1156000D03*
X77293Y1129729D03*
X58000Y1206000D03*
X46000Y1218000D03*
X60000Y1194000D03*
X61000Y1173000D03*
X54000Y1184000D03*
X44000Y1194000D03*
X42000Y1242000D03*
X50000Y1244000D03*
X42000Y1266000D03*
X58000Y1250000D03*
Y1222000D03*
X39500Y1231000D03*
X51800Y1231600D03*
X50100Y1261500D03*
X42000Y1290000D03*
X50000Y1318000D03*
X40000Y1278000D03*
Y1298000D03*
X44000Y1306000D03*
X58000Y1312000D03*
Y1292000D03*
Y1272000D03*
X52000Y1296300D03*
X61000Y1363500D03*
X52500Y1368500D03*
X39000Y1333500D03*
X44000Y1326000D03*
Y1340000D03*
X54000Y1330000D03*
X72000Y1360000D03*
X83800Y1365900D03*
X84000Y1352000D03*
X81500Y1382000D03*
Y1416500D03*
Y1404000D03*
X71800Y1373900D03*
X83800Y1391900D03*
X70500Y1378500D03*
X69400Y1402900D03*
X39500Y1407900D03*
X55600Y1381700D03*
X48900Y1390500D03*
X60900D03*
X56700Y1400100D03*
X60600Y1423600D03*
X68800Y1417800D03*
X58800Y1412400D03*
X49000Y1413300D03*
X72900Y1393600D03*
X74900Y1408800D03*
X75600Y1420300D03*
X61500Y1380000D03*
X86900Y1451000D03*
X70400Y1444500D03*
X79000Y1436400D03*
X76200Y1430700D03*
X66500Y1433500D03*
X53100Y1430700D03*
X42600Y1444200D03*
X49100Y1448400D03*
X68500Y1454600D03*
X74500Y1461800D03*
X72300Y1469800D03*
X59000Y1444500D03*
X77000Y1449000D03*
X59000Y1472000D03*
X58100Y1459300D03*
X83500Y1469500D03*
X85200Y1515000D03*
X58500Y1519000D03*
X72000Y1514000D03*
X53500Y1519000D03*
X63000Y1482300D03*
X42700Y1500000D03*
X72700Y1480500D03*
X46500Y1484900D03*
X64100Y1495400D03*
X73000Y1491200D03*
X43300Y1518500D03*
X49500Y1505000D03*
X45400Y1523800D03*
X85000Y1490000D03*
X54500Y1574000D03*
X73900Y1535900D03*
X80000Y1531600D03*
X54300Y1541200D03*
X59500Y1541000D03*
X57500Y1562000D03*
X57000Y1568500D03*
X46600Y1541100D03*
X45300Y1563600D03*
X45900Y1532800D03*
X37900Y1570000D03*
X38800Y1541700D03*
X38300Y1561800D03*
X44400Y1592100D03*
X38300Y1579600D03*
X71600Y1607700D03*
X50600Y1589300D03*
Y1582800D03*
Y1595300D03*
Y1601300D03*
X55300Y1601100D03*
Y1595100D03*
Y1582600D03*
Y1589100D03*
X68700Y1603900D03*
X55400Y1613300D03*
X58500Y1607700D03*
X43200Y1634800D03*
X59500Y1667000D03*
X70000Y1668000D03*
X75500Y1679000D03*
X86000D03*
Y1669000D03*
X76000Y1646000D03*
X86000D03*
X76000Y1634000D03*
X86000D03*
Y1659500D03*
X75500D03*
X54000Y1646500D03*
X64500Y1646000D03*
X57500Y1634500D03*
X64000Y1634000D03*
X64500Y1658500D03*
X53500Y1659000D03*
X42500Y1699500D03*
X44600Y1724400D03*
X44900Y1706800D03*
X56000Y1695000D03*
Y1704500D03*
Y1712500D03*
X55500Y1723500D03*
X69000Y1684500D03*
X80500D03*
X62500Y1691500D03*
X65000Y1724000D03*
X62500Y1709000D03*
X72500Y1717000D03*
Y1699000D03*
X62500Y1700000D03*
X60000Y1730000D03*
X86500Y1713610D03*
Y1700110D03*
Y1726000D03*
X48400Y1746900D03*
X41600D03*
X38800Y1775000D03*
X53000Y1750500D03*
X36700Y1764700D03*
X56500Y1769300D03*
X44900Y1740300D03*
X64500Y1758500D03*
X55500Y1735500D03*
X65000Y1735000D03*
X79000Y1766500D03*
X65000Y1749000D03*
Y1768000D03*
Y1742500D03*
X71500Y1760000D03*
X72500Y1733000D03*
X87000Y1774110D03*
X42000Y1784400D03*
X81000Y1802000D03*
X73000Y1813000D03*
X64500Y1821500D03*
Y1812000D03*
Y1801500D03*
X65000Y1790000D03*
X72500Y1830000D03*
X72000Y1798000D03*
X86500Y1793110D03*
X39179Y1792306D03*
X39700Y1869700D03*
X46700Y1857700D03*
X46500Y1850200D03*
X44500Y1833500D03*
X46500Y1844000D03*
Y1865500D03*
X75500Y1838500D03*
X63500Y1863000D03*
Y1856000D03*
X64000Y1844500D03*
Y1834000D03*
X73000Y1847000D03*
X85100Y1844500D03*
X85700Y1852300D03*
X45100Y1933400D03*
X54500Y1889500D03*
X63500Y1928000D03*
X61500Y1922500D03*
X46000Y1923000D03*
X54000Y1928500D03*
X36500Y1900500D03*
X63500Y1963000D03*
X63594Y1935500D03*
X61600Y1954700D03*
X41100Y1957500D03*
X55300Y1959100D03*
X43500Y1945000D03*
X49053Y1951747D03*
X135000Y50000D03*
Y70000D03*
X128500Y89000D03*
X118000Y54500D03*
X124000Y74500D03*
X105000Y55000D03*
Y45000D03*
X95000D03*
X115000D03*
X125000D03*
X135000D03*
X137200Y123600D03*
X127700Y119200D03*
X128700Y104200D03*
X131000Y138100D03*
X118000Y124500D03*
X119000Y109500D03*
X118000Y142500D03*
X95000Y143000D03*
X105000D03*
X95000Y125000D03*
X105000D03*
X95000Y134000D03*
X129000Y160100D03*
X137900Y171400D03*
X131000Y150100D03*
X118000Y154500D03*
X95000Y155000D03*
X105000D03*
X131800Y289700D03*
X130900Y259100D03*
X114000Y296000D03*
X106000D03*
X96000D03*
X102000Y312000D03*
X104000Y304000D03*
X94000D03*
Y312000D03*
Y320000D03*
X111500Y390000D03*
X101300Y390100D03*
X105500Y390000D03*
X134000Y396000D03*
X118000D03*
Y386000D03*
X134000D03*
X105500Y406500D03*
X101500D03*
X107000Y426500D03*
X98000D03*
X102500D03*
X111200Y426400D03*
X110500Y406500D03*
X122500Y450500D03*
X117000Y449000D03*
X89800Y446000D03*
X136000Y447000D03*
X131000D03*
X91900Y410500D03*
X88500Y426500D03*
X134000Y404500D03*
X118000Y424000D03*
Y404000D03*
X130000Y432000D03*
X134000Y414000D03*
X118000D03*
X134000Y424000D03*
X129000Y485500D03*
X120000D03*
Y501500D03*
X110800Y482600D03*
X99800Y482000D03*
X110800Y488600D03*
X100000Y488000D03*
X110800Y500600D03*
X100000Y500000D03*
X129000Y501500D03*
X100000Y494000D03*
X110800Y494600D03*
X129000Y493500D03*
X120000D03*
X137000Y501500D03*
Y493000D03*
X136500Y485500D03*
X122500Y457500D03*
Y463500D03*
X121500Y475500D03*
X122500Y469500D03*
X117000Y455000D03*
Y460500D03*
Y466000D03*
Y471500D03*
X89800Y452900D03*
Y459000D03*
X111500Y473000D03*
X99500D03*
X89800Y464800D03*
X135500Y454000D03*
Y461000D03*
Y474500D03*
Y468000D03*
X130500Y454000D03*
Y461000D03*
Y468000D03*
Y474500D03*
X129000Y517500D03*
X100000Y512000D03*
X129000Y509500D03*
X110800Y512600D03*
X120000Y517500D03*
X100000Y506000D03*
X110800Y506600D03*
X120000Y509500D03*
Y523500D03*
X129000D03*
X137000Y510000D03*
X137500Y523500D03*
X100000Y519100D03*
X137500Y517500D03*
X117000Y530000D03*
X90630Y602020D03*
X103100Y587600D03*
X87595Y581300D03*
X112800Y653500D03*
X108200Y655825D03*
X88967Y659749D03*
X90674Y663367D03*
X121500Y683500D03*
X119576Y687008D03*
X120702Y690847D03*
X100600Y670600D03*
X134100Y674500D03*
X119000Y673300D03*
X87310Y676796D03*
X124800Y696600D03*
X129800Y696800D03*
X98000Y674327D03*
X102913Y673973D03*
X107113Y674001D03*
X108500Y695500D03*
X103500D03*
X115000Y704500D03*
X99001Y694866D03*
X125000Y734000D03*
X116500Y752000D03*
X125000Y751000D03*
X125500Y741500D03*
X130000Y736500D03*
X125000Y758500D03*
X120500Y732500D03*
X120000Y717500D03*
X107000Y802400D03*
Y798200D03*
X106882Y794201D03*
X123000Y808500D03*
X114500Y805500D03*
X123000Y800000D03*
X122500Y792500D03*
X114000Y800000D03*
X113500Y792500D03*
X130000Y800000D03*
X129500Y792500D03*
X121500Y783500D03*
X121000Y776000D03*
X129500Y782000D03*
X129000Y774500D03*
X115200Y784200D03*
X115000Y773200D03*
X121000Y767900D03*
X95500Y841500D03*
X124500Y858000D03*
X123500Y842500D03*
Y816000D03*
X115000Y813000D03*
X129200Y830400D03*
X129800Y813500D03*
X124500Y825100D03*
X134500Y840500D03*
X90500Y831500D03*
X137500Y903000D03*
X135500Y909000D03*
X124000D03*
X113500Y909500D03*
X103500D03*
X94000Y910500D03*
X116053Y903247D03*
X127000Y903000D03*
X90000Y893000D03*
X102500Y893500D03*
X117500Y893000D03*
X135000D03*
X134500Y885500D03*
X137500Y876500D03*
X125000Y868500D03*
X107000Y903000D03*
X124500Y876500D03*
X126000Y892500D03*
X96053Y903247D03*
X125500Y944000D03*
X105000Y958000D03*
X96500Y916500D03*
X107000Y918000D03*
X135000D03*
X135500Y927500D03*
X115000Y920000D03*
X125500D03*
X126000Y930000D03*
X115500D03*
X99000Y953000D03*
X88500Y940500D03*
X120000Y916000D03*
X126000Y954000D03*
X124618Y959244D03*
X110000Y949500D03*
X117529Y948844D03*
X93000Y925500D03*
X133500Y938000D03*
X134000Y990500D03*
X125000Y967000D03*
X130500Y966000D03*
X124000Y971500D03*
X117000Y1008500D03*
X105500Y996000D03*
X95500Y999000D03*
X106500Y1008500D03*
X104000Y1014000D03*
X119000Y975000D03*
X136500Y967000D03*
X108500Y964000D03*
Y971000D03*
X114800Y1005000D03*
X135000Y975500D03*
X91400Y1064100D03*
X95500Y1064000D03*
X97250Y1023500D03*
X110500Y1041500D03*
X111500Y1030000D03*
Y1020000D03*
X110500Y1064500D03*
Y1051000D03*
X103500Y1042000D03*
Y1028500D03*
X116500Y1049000D03*
Y1035500D03*
Y1062500D03*
X117500Y1023500D03*
X120000Y1108000D03*
Y1102000D03*
X115000Y1108500D03*
X110500Y1112000D03*
X103500Y1073500D03*
X104500Y1095000D03*
X116500Y1076000D03*
X109000Y1083500D03*
X89000Y1167400D03*
X101500Y1127500D03*
X106000D03*
X97000D03*
X97500Y1132500D03*
X118500Y1166000D03*
X105000Y1196000D03*
X119300Y1191400D03*
X119500Y1177500D03*
Y1205500D03*
X92000Y1214500D03*
X104500Y1208000D03*
X94000Y1189000D03*
X91500Y1200000D03*
X99000Y1265500D03*
X119000Y1269000D03*
X117500Y1251000D03*
X112000Y1250500D03*
Y1244500D03*
X119300Y1245400D03*
Y1219400D03*
X119500Y1231500D03*
X124000Y1270000D03*
X104500Y1219500D03*
X92000Y1254000D03*
X103500Y1229000D03*
X92000Y1241500D03*
X103000Y1244900D03*
X91500Y1229000D03*
X99500Y1310000D03*
Y1294000D03*
X98000Y1282000D03*
X123800Y1283900D03*
X113800Y1287900D03*
X114000Y1274000D03*
X123800Y1311900D03*
X124000Y1298000D03*
X114000Y1318000D03*
X92000Y1295500D03*
X91500Y1314500D03*
X114500Y1296500D03*
X97800Y1327900D03*
X123800Y1337900D03*
X124000Y1324000D03*
X113800Y1331900D03*
X115800Y1363900D03*
X116000Y1350000D03*
X123800Y1365900D03*
X124000Y1352000D03*
X114500Y1370500D03*
X93800Y1353900D03*
X94000Y1340000D03*
Y1366000D03*
X90800Y1331200D03*
X105500Y1415000D03*
X99600Y1416500D03*
X100500Y1384500D03*
Y1389000D03*
X124000Y1376500D03*
X114000Y1376000D03*
X93800Y1379900D03*
Y1393200D03*
X93600Y1407100D03*
X97500Y1412000D03*
X89700Y1409700D03*
X110000Y1418000D03*
X137000Y1429200D03*
X126600Y1461500D03*
X133500Y1467100D03*
X132200Y1424800D03*
X94000Y1427800D03*
X87200Y1431900D03*
X87700Y1446500D03*
X87300Y1436000D03*
X95500Y1468000D03*
X103700Y1470300D03*
X113024Y1452079D03*
X117122Y1448001D03*
X117195Y1456070D03*
X121338Y1452021D03*
X117024Y1452000D03*
X87200Y1440000D03*
X99800Y1455600D03*
X109500Y1438000D03*
X98500Y1428400D03*
X117000Y1435200D03*
X133799Y1440699D03*
X93000Y1518700D03*
X94000Y1514000D03*
X87900Y1523400D03*
X124500Y1524000D03*
X91300Y1488600D03*
X97000Y1503100D03*
X93500Y1482700D03*
X99170Y1485790D03*
X129000Y1555500D03*
X111500Y1537500D03*
X122000Y1558000D03*
X114000Y1552000D03*
X122000D03*
X114000Y1558000D03*
X122000Y1564000D03*
X121800Y1569929D03*
X114000Y1564000D03*
X122000Y1576000D03*
X102000Y1544000D03*
Y1562000D03*
Y1550000D03*
Y1556000D03*
Y1568000D03*
X94000D03*
X116000Y1576000D03*
X115900Y1569700D03*
X129000Y1535000D03*
X136000Y1568000D03*
X94000Y1556000D03*
X129000Y1549000D03*
X122000Y1538000D03*
X136000Y1542000D03*
X122000Y1546000D03*
X129000Y1542500D03*
X136000Y1536000D03*
X114000Y1546000D03*
X128000Y1568000D03*
X136000Y1562000D03*
Y1555000D03*
X129000Y1562500D03*
X136000Y1548000D03*
X119000Y1529500D03*
X94000Y1550000D03*
Y1562000D03*
X136000Y1528000D03*
X122000Y1584000D03*
X116000D03*
Y1592000D03*
X122000D03*
X116000Y1600000D03*
X122000Y1612000D03*
X104000Y1605500D03*
X116000Y1612000D03*
X122000Y1600000D03*
X128000Y1606000D03*
X94500Y1605500D03*
X113500D03*
X117500Y1679000D03*
X125000D03*
X107500D03*
X117500Y1669000D03*
X127500D03*
X97000D03*
X107000D03*
X127000Y1646000D03*
X138000Y1634000D03*
X137500Y1659500D03*
X118000Y1646000D03*
X138000D03*
X117000Y1633500D03*
X127500Y1633000D03*
Y1659500D03*
X117500D03*
X108000Y1646000D03*
X106000Y1634000D03*
X107000Y1659500D03*
X96000Y1646000D03*
X96500Y1634000D03*
X97000Y1659500D03*
X122000Y1685500D03*
X91000Y1685000D03*
X103000D03*
X112500D03*
X108500Y1727000D03*
X98500Y1717000D03*
Y1696500D03*
X99000Y1707000D03*
X97500Y1679500D03*
X109500Y1719500D03*
X110000Y1709500D03*
X109500Y1699000D03*
X119500Y1710110D03*
Y1696610D03*
Y1725110D03*
X111500Y1768500D03*
X117500Y1732000D03*
X119500Y1760000D03*
X97500Y1775500D03*
X108268Y1777300D03*
X119500Y1747110D03*
X138000Y1824000D03*
X110500Y1801000D03*
X88500Y1785000D03*
X97500Y1796000D03*
X98000Y1786000D03*
X107768Y1789110D03*
X120000Y1811500D03*
X119500Y1796500D03*
X114000Y1843500D03*
X97000Y1850500D03*
X99500Y1862500D03*
X106500D03*
X114500D03*
X122500D03*
X120500Y1836500D03*
Y1850500D03*
X108500Y1851610D03*
X116948Y1892000D03*
X124500Y1892403D03*
X132000Y1892000D03*
X118000Y1922000D03*
X184000Y55500D03*
X174000D03*
X164000D03*
X153000Y90500D03*
X154000Y75500D03*
X145000Y45000D03*
X155000D03*
X165000D03*
X175000D03*
X185000D03*
X180500Y112000D03*
X186000Y143000D03*
X187500Y130500D03*
X167000D03*
X176000Y131000D03*
X165500Y95500D03*
X174500Y143500D03*
X171500Y105500D03*
X170500Y120500D03*
X146500Y131859D03*
X154000Y105500D03*
X147600Y150900D03*
X165300Y145200D03*
X173500Y151500D03*
X185500D03*
X138800Y162100D03*
X141300Y298100D03*
X182000Y296000D03*
X172000D03*
X162000D03*
X142000Y291000D03*
X187500Y338000D03*
X180850Y348800D03*
X184500Y325500D03*
X143400Y318700D03*
X174000Y316000D03*
X164000D03*
X172000Y310000D03*
X182000D03*
X184000Y303000D03*
X176000Y302000D03*
X166000D03*
X143300Y343400D03*
X151300Y298200D03*
X188500Y364100D03*
X188300Y368600D03*
X181800Y369000D03*
X181100Y364050D03*
X150000Y386000D03*
Y396000D03*
X186600Y425750D03*
X161600Y445900D03*
X161900Y451600D03*
X174500Y432000D03*
X162000D03*
X145500Y427000D03*
X142000Y432000D03*
X150000Y404000D03*
Y414000D03*
Y424000D03*
X186500Y498000D03*
X144000Y501500D03*
X173600Y498800D03*
X169200Y482800D03*
X157100Y500000D03*
X144000Y493500D03*
Y486182D03*
X162000Y457600D03*
X161900Y463300D03*
X188500Y474500D03*
X186500Y513500D03*
X173700Y513900D03*
X144000Y517500D03*
X173500Y506000D03*
X186500D03*
Y519000D03*
X174900Y523300D03*
X156800Y515400D03*
Y506900D03*
X144600Y533800D03*
X147500Y551500D03*
X182600Y546900D03*
X180500Y595000D03*
X171600Y595400D03*
X145500Y604000D03*
X141800Y559250D03*
X150500Y596000D03*
X153500Y574359D03*
X140700Y576600D03*
X152700Y618803D03*
X170349Y619949D03*
X167300Y653800D03*
X159700Y652000D03*
X175800Y617635D03*
X164950Y615700D03*
X180500Y627771D03*
X165600Y630269D03*
X151432Y661741D03*
X148995Y658568D03*
X185000Y673500D03*
X188100Y689100D03*
X176000Y679000D03*
Y665500D03*
X162300Y659100D03*
X183500Y698000D03*
X184700Y663900D03*
X165500Y677500D03*
X184500Y708500D03*
X181000Y729000D03*
Y715500D03*
X182500Y758500D03*
Y745000D03*
X172000Y757500D03*
X181500Y738500D03*
X169100Y722100D03*
X169000Y795500D03*
X163500Y805500D03*
X178000Y797500D03*
X187900Y785300D03*
X175000Y786500D03*
X173500Y777500D03*
Y764000D03*
X181700Y768400D03*
X165000Y786000D03*
X171500Y819500D03*
X177500Y812000D03*
Y826500D03*
X145500Y856500D03*
X140500Y846500D03*
X157500Y858000D03*
X185000Y843500D03*
X145500Y885000D03*
X143000Y910500D03*
X146000Y893000D03*
X184500Y879000D03*
Y865500D03*
X154700Y909700D03*
X156300Y877200D03*
X156500Y889000D03*
X187000Y891000D03*
X153500Y941000D03*
X141000Y938500D03*
X144000Y919500D03*
Y929000D03*
X154500Y926500D03*
X185000Y917500D03*
X182000Y950500D03*
X174000Y1012400D03*
X184000Y987500D03*
X146800Y1018900D03*
X143900Y1022700D03*
X166300Y1021300D03*
X182500Y1041500D03*
X183500Y1065500D03*
X182000Y1029500D03*
Y1016000D03*
X171000Y1046000D03*
Y1032500D03*
X175000Y1059000D03*
X160500Y1053500D03*
X181000Y1051000D03*
X164700Y1033600D03*
X176000Y1018500D03*
X171000Y1068000D03*
X166000Y1080000D03*
X173000Y1082000D03*
X165000Y1097000D03*
X181000Y1098500D03*
X175000Y1072500D03*
X160500Y1067000D03*
X187500Y1103500D03*
Y1090000D03*
X170000Y1103000D03*
Y1089500D03*
X157000Y1101500D03*
X159500Y1087500D03*
X181000Y1112500D03*
Y1079500D03*
X154600Y1111000D03*
X158500Y1075800D03*
X158595Y1110789D03*
X155000Y1130500D03*
Y1125000D03*
Y1120000D03*
X147500Y1165500D03*
X177102Y1129800D03*
X171502Y1129547D03*
X147500Y1186000D03*
X178644Y1202519D03*
X163344Y1181200D03*
X161500Y1227500D03*
X147500Y1221500D03*
X146500Y1241500D03*
X147000Y1265500D03*
X183500Y1241500D03*
X165000Y1264500D03*
X147500Y1288000D03*
Y1311000D03*
X164500Y1299500D03*
X147500Y1332000D03*
X147000Y1348000D03*
X147500Y1366500D03*
X147000Y1377000D03*
X146500Y1417619D03*
X148300Y1465000D03*
X173375Y1432500D03*
X149686Y1460007D03*
X152500Y1456000D03*
X174500Y1503500D03*
Y1509500D03*
X174000Y1515500D03*
Y1522000D03*
X148000Y1550000D03*
X170000Y1541000D03*
X148000Y1558000D03*
Y1528000D03*
Y1542000D03*
X168500Y1533500D03*
X170000Y1555000D03*
X161400Y1543500D03*
X150000Y1576000D03*
X156000Y1570000D03*
X154000Y1564000D03*
X170000Y1548500D03*
X169500Y1561500D03*
X161300Y1563100D03*
X148000Y1564000D03*
X156000Y1576000D03*
X168500Y1526000D03*
X166898Y1567102D03*
X150000Y1570000D03*
X156000Y1582000D03*
X156500Y1591000D03*
X150500Y1582000D03*
Y1591000D03*
X172000Y1606000D03*
X182500Y1599400D03*
X146000Y1612000D03*
X148000Y1606000D03*
X182500Y1592000D03*
X164000Y1606000D03*
X156500Y1600000D03*
X156000Y1606000D03*
X150500Y1600000D03*
X138500Y1606000D03*
X182500Y1584500D03*
X141500Y1673000D03*
X176000Y1646000D03*
X166000D03*
X158000D03*
X148000D03*
X176000Y1632000D03*
X178000Y1659500D03*
X167500Y1632500D03*
X170000Y1659500D03*
X149000Y1632500D03*
X159000D03*
Y1659500D03*
X148500Y1660000D03*
X139000Y1696500D03*
Y1712500D03*
X138500Y1727500D03*
X181500Y1716500D03*
X158500D03*
X167500Y1716000D03*
X182000Y1726000D03*
Y1704000D03*
X168500Y1705000D03*
X158500D03*
X184500Y1696500D03*
X163000Y1697000D03*
X174268Y1697110D03*
X152000D03*
Y1710610D03*
Y1725610D03*
X185000Y1738500D03*
X183600Y1765100D03*
X169000Y1781500D03*
X162500Y1773000D03*
X152500Y1771110D03*
X173268Y1776000D03*
X139000Y1800500D03*
X156500Y1782000D03*
X155500Y1798500D03*
X166500Y1798000D03*
X179000Y1798500D03*
X185500Y1804500D03*
X186000Y1790000D03*
X162000D03*
X172768Y1790110D03*
X152000D03*
X139000Y1851000D03*
X138500Y1839500D03*
X185000Y1852500D03*
X161500D03*
X183100Y1838300D03*
X160500Y1877500D03*
X173000Y1852610D03*
X151500Y1851110D03*
X161000Y1901500D03*
X194000Y55500D03*
X195000Y45000D03*
X200000Y55000D03*
Y65000D03*
Y75000D03*
Y85000D03*
X190500Y105000D03*
X189500Y120000D03*
X200000Y100000D03*
Y120000D03*
Y140000D03*
X191900Y167700D03*
X191700Y186500D03*
X201089Y181700D03*
X197500Y151500D03*
X191900Y244600D03*
X191800Y234900D03*
Y221100D03*
X191600Y206900D03*
X201500Y208000D03*
X201000Y222500D03*
X200500Y235000D03*
Y195900D03*
X202000Y295000D03*
Y274000D03*
Y254000D03*
X201089Y282600D03*
X202000Y264000D03*
Y340000D03*
Y328000D03*
X201089Y305500D03*
Y315500D03*
X201500Y397500D03*
Y378000D03*
X202000Y366500D03*
Y353000D03*
X192600Y392600D03*
X192471Y397355D03*
X201089Y388400D03*
X200500Y437500D03*
X201000Y430500D03*
X201089Y407000D03*
X200000Y420500D03*
X192400Y401900D03*
X192300Y410950D03*
X192409Y417655D03*
X190239Y447449D03*
X195600Y447500D03*
X192000Y490000D03*
Y498000D03*
X200300Y498100D03*
X199500Y489400D03*
X189900Y467500D03*
Y460500D03*
X190400Y453500D03*
X195000Y467500D03*
X194500Y474500D03*
X195000Y460500D03*
X195500Y453500D03*
X192000Y513500D03*
Y506000D03*
X190200Y523400D03*
X201089Y523500D03*
X193600Y519100D03*
X200100Y513600D03*
X199800Y506000D03*
X201200Y519200D03*
X201500Y544500D03*
X201089Y529500D03*
X201500Y552500D03*
X192400Y529400D03*
X191900Y538200D03*
X201500Y535000D03*
X192000Y543500D03*
X190500Y550500D03*
X202000Y578000D03*
Y586000D03*
Y595000D03*
X193700D03*
X194400Y586000D03*
X201089Y558000D03*
X201500Y564000D03*
X201089Y570600D03*
X202000Y607500D03*
X196500Y641500D03*
X192600Y633000D03*
X201500Y621500D03*
X202000Y650500D03*
X194000Y628500D03*
Y615000D03*
X192500Y645000D03*
X195000Y670000D03*
X197500Y685000D03*
X197000Y704000D03*
X202000Y676500D03*
X192500Y658500D03*
X191500Y692500D03*
X193100Y679000D03*
X196000Y718500D03*
X195500Y739000D03*
X197500Y753000D03*
X202000Y710000D03*
Y740500D03*
X191500Y724000D03*
Y710500D03*
Y746500D03*
X196000Y789500D03*
X196500Y797000D03*
X202000Y765000D03*
Y786000D03*
Y807500D03*
X191500Y760000D03*
X194500Y782500D03*
Y769000D03*
X196800Y828500D03*
X197000Y815000D03*
X190000Y823500D03*
X190500Y831000D03*
X201500Y835500D03*
X192500Y853000D03*
Y839500D03*
X192000Y879000D03*
Y865500D03*
X194000Y907000D03*
Y893500D03*
X192000Y934500D03*
Y921000D03*
Y962000D03*
Y948500D03*
X192500Y985500D03*
Y972000D03*
X195500Y1001000D03*
X190000Y1052000D03*
X195500Y1014500D03*
X193500Y1042500D03*
Y1029000D03*
X195000Y1061000D03*
Y1086500D03*
X194500Y1100500D03*
X195000Y1074500D03*
X201000Y1106500D03*
Y1093000D03*
X191800Y1280900D03*
X192500Y1543500D03*
Y1554000D03*
Y1533000D03*
Y1562500D03*
X196500Y1586000D03*
Y1595000D03*
X192500Y1617000D03*
Y1626500D03*
Y1634000D03*
Y1670500D03*
Y1664000D03*
X198500Y1713500D03*
X198000Y1691500D03*
X197500Y1776500D03*
X198000Y1754000D03*
Y1735500D03*
Y1818500D03*
X197500Y1800500D03*
X198500Y1859500D03*
X198000Y1838500D03*
X195000Y1874000D03*
X200000Y1882000D03*
X201500Y1900500D03*
X190500Y1924000D03*
X201000Y1923000D03*
X195500Y1905000D03*
X822950Y378150D03*
G54D21*
X80709Y161889D03*
Y171889D03*
Y181889D03*
Y191889D03*
Y204409D03*
Y214409D03*
Y224409D03*
Y234409D03*
Y244409D03*
Y256929D03*
Y266929D03*
Y276929D03*
Y286929D03*
X110709Y161889D03*
Y171889D03*
X100709Y161889D03*
Y171889D03*
X90709Y161889D03*
Y171889D03*
X110709Y181889D03*
Y191889D03*
X100709Y181889D03*
Y191889D03*
X90709Y181889D03*
Y191889D03*
X110709Y204409D03*
Y214409D03*
Y224409D03*
Y234409D03*
Y244409D03*
X100709Y204409D03*
Y214409D03*
Y224409D03*
Y234409D03*
Y244409D03*
X90709Y204409D03*
Y214409D03*
Y224409D03*
Y234409D03*
Y244409D03*
X110709Y256929D03*
Y266929D03*
X100709Y256929D03*
Y266929D03*
X90709Y256929D03*
Y266929D03*
X110709Y276929D03*
Y286929D03*
X100709Y276929D03*
Y286929D03*
X90709Y276929D03*
Y286929D03*
X179606Y161889D03*
Y171889D03*
X169606Y161889D03*
Y171889D03*
X159606Y161889D03*
Y171889D03*
X149606Y161889D03*
Y171889D03*
X179606Y181889D03*
Y191889D03*
X169606Y181889D03*
Y191889D03*
X159606Y181889D03*
Y191889D03*
X149606Y181889D03*
Y191889D03*
X179606Y204409D03*
Y214409D03*
Y224409D03*
Y234409D03*
Y244409D03*
X169606Y204409D03*
Y214409D03*
Y224409D03*
Y234409D03*
Y244409D03*
X159606Y204409D03*
Y214409D03*
Y224409D03*
Y234409D03*
Y244409D03*
X149606Y204409D03*
Y214409D03*
Y224409D03*
Y234409D03*
Y244409D03*
X179606Y256929D03*
Y266929D03*
X169606Y256929D03*
Y266929D03*
X159606Y256929D03*
Y266929D03*
X149606Y256929D03*
Y266929D03*
X179606Y276929D03*
Y286929D03*
X169606Y276929D03*
Y286929D03*
X159606Y276929D03*
Y286929D03*
X149606Y276929D03*
Y286929D03*
X822950Y293850D03*
G54D13*
X15906Y48110D03*
Y58110D03*
Y68110D03*
Y78110D03*
Y88110D03*
Y481339D03*
Y491339D03*
Y501339D03*
Y511339D03*
Y521339D03*
Y741181D03*
Y751181D03*
Y761181D03*
Y771181D03*
Y781181D03*
Y1187323D03*
Y1197323D03*
Y1207323D03*
Y1217323D03*
Y1227323D03*
Y1447165D03*
Y1457165D03*
Y1467165D03*
Y1477165D03*
Y1487165D03*
Y1880394D03*
Y1890394D03*
Y1900394D03*
Y1910394D03*
Y1920394D03*
X138937Y1778819D03*
X128937D03*
X118937D03*
X165000Y1370500D03*
Y1390500D03*
Y1380500D03*
X822950Y321950D03*
G54D22*
X96457Y1747835D03*
Y1823031D03*
X178937Y1328740D03*
X161417Y1747835D03*
Y1823031D03*
X822950Y209550D03*
G54D23*
G01X-448201Y-66763D02*
X-480201D01*
G01X-448201Y-82763D02*
Y-162763D01*
G01Y-118263D02*
X752899D01*
G01X-448201Y-162763D02*
X752899D01*
G01X-452201Y-66763D02*
G02I-12000J0D01*
G01X-457351D02*
G02I-6850J0D01*
G01X-464201Y-82763D02*
Y-50763D01*
G01X-448201Y-82763D02*
X752899D01*
G01X-34601D02*
Y-162763D01*
G01X102899Y-82763D02*
Y-162763D01*
G01X217899Y-82763D02*
Y-162763D01*
G01X385399Y-82763D02*
Y-162763D01*
G01X555399Y-82763D02*
Y-162763D01*
G01X752899Y-82763D02*
Y-162763D01*
G01X780899Y-66763D02*
G02I-12000J0D01*
G01X775749D02*
G02I-6850J0D01*
G01X768899Y-82763D02*
Y-50763D01*
G01X784899Y-66763D02*
X752899D01*
G54D14*
X27559Y157480D03*
X179134Y1889764D03*
X822950Y237650D03*
G54D24*
G01X-430254Y-152763D02*
Y-135263D01*
G01X-421958D02*
X-430254Y-146055D01*
G01X-420648Y-152763D02*
X-426543Y-141097D01*
G01X-412973Y-152763D02*
Y-135263D01*
X-402929Y-152763D01*
Y-135263D01*
G01X-390451Y-152763D02*
X-392198Y-152471D01*
X-393726Y-151305D01*
X-395036Y-149555D01*
X-395910Y-147513D01*
X-396346Y-145180D01*
Y-142846D01*
X-395910Y-140513D01*
X-395036Y-138471D01*
X-393726Y-136722D01*
X-392198Y-135555D01*
X-390451Y-135263D01*
X-388705Y-135555D01*
X-387176Y-136722D01*
X-385866Y-138471D01*
X-384992Y-140513D01*
X-384556Y-142846D01*
Y-145180D01*
X-384992Y-147513D01*
X-385866Y-149555D01*
X-387176Y-151305D01*
X-388705Y-152471D01*
X-390451Y-152763D01*
G01X-377536D02*
X-368366Y-135263D01*
G01X-377536D02*
X-368366Y-152763D01*
G01X-362001Y-158596D02*
X-348901D01*
G01X-342099Y-152763D02*
Y-135263D01*
X-333803D01*
G01X-336859Y-143721D02*
X-342099D01*
G01X-325910Y-152763D02*
X-320451Y-135263D01*
X-314992Y-152763D01*
G01X-316958Y-146638D02*
X-323945D01*
G01X-307973Y-152763D02*
Y-135263D01*
X-297929Y-152763D01*
Y-135263D01*
G01X-263148Y-136722D02*
X-264458Y-135846D01*
X-265986Y-135263D01*
X-267733D01*
X-269698Y-136138D01*
X-271226Y-137596D01*
X-272318Y-139347D01*
X-273191Y-142263D01*
X-273410Y-144888D01*
X-272973Y-147513D01*
X-272318Y-149263D01*
X-271008Y-151013D01*
X-269479Y-152180D01*
X-267951Y-152763D01*
X-266423D01*
X-264894Y-152180D01*
X-263584Y-151305D01*
X-262492Y-150139D01*
G01X-250451Y-152763D02*
X-252198Y-152471D01*
X-253726Y-151305D01*
X-255036Y-149555D01*
X-255910Y-147513D01*
X-256346Y-145180D01*
Y-142846D01*
X-255910Y-140513D01*
X-255036Y-138471D01*
X-253726Y-136722D01*
X-252198Y-135555D01*
X-250451Y-135263D01*
X-248705Y-135555D01*
X-247176Y-136722D01*
X-245866Y-138471D01*
X-244992Y-140513D01*
X-244556Y-142846D01*
Y-145180D01*
X-244992Y-147513D01*
X-245866Y-149555D01*
X-247176Y-151305D01*
X-248705Y-152471D01*
X-250451Y-152763D01*
G01X-237973D02*
Y-135263D01*
X-227929Y-152763D01*
Y-135263D01*
G01X-215451D02*
Y-152763D01*
G01X-220473Y-135263D02*
X-210429D01*
G01X-202318Y-152763D02*
Y-135263D01*
X-196859D01*
X-195113Y-136138D01*
X-194021Y-137305D01*
X-193584Y-139638D01*
X-194021Y-141972D01*
X-195331Y-143430D01*
X-196859Y-144305D01*
X-202318D01*
G01X-196859D02*
X-193584Y-152763D01*
G01X-180451D02*
X-182198Y-152471D01*
X-183726Y-151305D01*
X-185036Y-149555D01*
X-185910Y-147513D01*
X-186346Y-145180D01*
Y-142846D01*
X-185910Y-140513D01*
X-185036Y-138471D01*
X-183726Y-136722D01*
X-182198Y-135555D01*
X-180451Y-135263D01*
X-178705Y-135555D01*
X-177176Y-136722D01*
X-175866Y-138471D01*
X-174992Y-140513D01*
X-174556Y-142846D01*
Y-145180D01*
X-174992Y-147513D01*
X-175866Y-149555D01*
X-177176Y-151305D01*
X-178705Y-152471D01*
X-180451Y-152763D01*
G01X-167318Y-135263D02*
Y-152763D01*
X-158584D01*
G01X-126205Y-143430D02*
X-125331Y-142555D01*
X-124676Y-141097D01*
X-124239Y-139054D01*
X-124676Y-137305D01*
X-125549Y-136138D01*
X-127078Y-135263D01*
X-132973D01*
Y-152763D01*
X-125768D01*
X-124239Y-151597D01*
X-123366Y-149846D01*
X-122929Y-147805D01*
X-123366Y-145763D01*
X-124676Y-144013D01*
X-126205Y-143430D01*
X-132973D01*
G01X-110451Y-152763D02*
X-112198Y-152471D01*
X-113726Y-151305D01*
X-115036Y-149555D01*
X-115910Y-147513D01*
X-116346Y-145180D01*
Y-142846D01*
X-115910Y-140513D01*
X-115036Y-138471D01*
X-113726Y-136722D01*
X-112198Y-135555D01*
X-110451Y-135263D01*
X-108705Y-135555D01*
X-107176Y-136722D01*
X-105866Y-138471D01*
X-104992Y-140513D01*
X-104556Y-142846D01*
Y-145180D01*
X-104992Y-147513D01*
X-105866Y-149555D01*
X-107176Y-151305D01*
X-108705Y-152471D01*
X-110451Y-152763D01*
G01X-98410D02*
X-92951Y-135263D01*
X-87492Y-152763D01*
G01X-89458Y-146638D02*
X-96445D01*
G01X-79818Y-152763D02*
Y-135263D01*
X-74359D01*
X-72613Y-136138D01*
X-71521Y-137305D01*
X-71084Y-139638D01*
X-71521Y-141972D01*
X-72831Y-143430D01*
X-74359Y-144305D01*
X-79818D01*
G01X-74359D02*
X-71084Y-152763D01*
G01X-62754D02*
Y-135263D01*
X-58388D01*
X-56641Y-136138D01*
X-55331Y-137305D01*
X-54239Y-139054D01*
X-53366Y-141097D01*
X-53148Y-144013D01*
X-53366Y-146930D01*
X-54239Y-148972D01*
X-55331Y-150722D01*
X-56641Y-151888D01*
X-58388Y-152763D01*
X-62754D01*
G01X-282378Y-107763D02*
Y-90263D01*
X-276701Y-104846D01*
X-271024Y-90263D01*
Y-107763D01*
G01X-259201D02*
X-260511Y-107471D01*
X-261821Y-106305D01*
X-262695Y-104263D01*
X-263131Y-101930D01*
X-262695Y-99596D01*
X-261821Y-97555D01*
X-260511Y-96388D01*
X-259201Y-96097D01*
X-257891Y-96388D01*
X-256581Y-97555D01*
X-255708Y-99596D01*
X-255489Y-101930D01*
X-255708Y-104263D01*
X-256581Y-106305D01*
X-257891Y-107471D01*
X-259201Y-107763D01*
G01X-237771Y-90263D02*
Y-107763D01*
G01Y-105139D02*
X-238644Y-106597D01*
X-239955Y-107471D01*
X-241483Y-107763D01*
X-243229Y-107180D01*
X-244539Y-105722D01*
X-245413Y-103972D01*
X-245631Y-101930D01*
X-245413Y-99888D01*
X-244539Y-98138D01*
X-243229Y-96680D01*
X-241483Y-96097D01*
X-239955Y-96388D01*
X-238863Y-96972D01*
X-237771Y-98138D01*
G01X-227476Y-99888D02*
X-220489D01*
X-221144Y-97846D01*
X-222236Y-96680D01*
X-223764Y-96097D01*
X-225293Y-96388D01*
X-226603Y-97263D01*
X-227476Y-99305D01*
X-227913Y-101055D01*
Y-102805D01*
X-227476Y-104555D01*
X-226384Y-106305D01*
X-225074Y-107471D01*
X-223546Y-107763D01*
X-222018Y-107180D01*
X-220489Y-105430D01*
G01X-206701Y-107763D02*
Y-90263D01*
G01X-222441Y169326D02*
Y39370D01*
G01D02*
G03X-214567Y31496I7874J0D01*
G01X-242126Y15000D02*
G03X-227126Y0I15000J0D01*
G01X-242126Y1953504D02*
Y15000D01*
G01X-215453Y19685D02*
G03I-6988J0D01*
G01X-84646Y0D02*
X-227126D01*
G01X-215453Y19685D02*
G03I-6988J0D01*
G01D02*
G03I-6988J0D01*
G01X-214567Y169326D02*
G03X-222441I-3937J0D01*
G01X-214567D02*
G03X-222441I-3937J0D01*
G01Y436255D02*
Y200034D01*
G01D02*
G03X-214567I3937J0D01*
G01X-222441D02*
G03X-214567I3937J0D01*
G01Y436255D02*
G03X-222441I-3937J0D01*
G01X-214567D02*
G03X-222441I-3937J0D01*
G01Y703184D02*
Y466963D01*
G01D02*
G03X-214567I3937J0D01*
G01X-222441D02*
G03X-214567I3937J0D01*
G01Y703184D02*
G03X-222441I-3937J0D01*
G01X-214567D02*
G03X-222441I-3937J0D01*
G01Y970901D02*
Y733892D01*
G01D02*
G03X-214567I3937J0D01*
G01X-222441D02*
G03X-214567I3937J0D01*
G01X-222441Y1234681D02*
Y997672D01*
G01X-214567Y970901D02*
G03X-222441I-3937J0D01*
G01Y997672D02*
G03X-214567I3937J0D01*
G01Y970901D02*
G03X-222441I-3937J0D01*
G01Y997672D02*
G03X-214567I3937J0D01*
G01X-222441Y1501610D02*
Y1265389D01*
G01D02*
G03X-214567I3937J0D01*
G01Y1234681D02*
G03X-222441I-3937J0D01*
G01Y1265389D02*
G03X-214567I3937J0D01*
G01Y1234681D02*
G03X-222441I-3937J0D01*
G01X-214567Y1501610D02*
G03X-222441I-3937J0D01*
G01X-214567D02*
G03X-222441I-3937J0D01*
G01Y1768539D02*
Y1532318D01*
G01D02*
G03X-214567I3937J0D01*
G01X-222441D02*
G03X-214567I3937J0D01*
G01Y1768539D02*
G03X-222441I-3937J0D01*
G01X-214567D02*
G03X-222441I-3937J0D01*
G01Y1799247D02*
G03X-214567I3937J0D01*
G01X-222441D02*
G03X-214567I3937J0D01*
G01X-222441Y1929134D02*
Y1799247D01*
G01X-214567Y1937008D02*
G03X-222441Y1929134I0J-7874D01*
G01X-227126Y1968504D02*
G03X-242126Y1953504I0J-15000D01*
G01X-215453Y1948819D02*
G03I-6988J0D01*
G01X-84638Y1968504D02*
X-227126D01*
G01X-215453Y1948819D02*
G03I-6988J0D01*
G01D02*
G03I-6988J0D01*
G01X-214567Y43307D02*
G03X-210630Y39370I3937J0D01*
G01X-214567Y43307D02*
G03X-210630Y39370I3937J0D01*
G01X-80709D02*
X-210630D01*
G01X-80709D02*
X-210630D01*
G01X-206693Y31496D02*
X-214567D01*
G01X-175984D02*
X-84646D01*
G01X-206693D02*
G03Y39370I0J3937D01*
G01X-175984D02*
G03Y31496I0J-3937D01*
G01X-206693D02*
X-214567D01*
G01X-84646Y0D02*
X-199567D01*
G01X-175984Y31496D02*
X-84646D01*
G01X-206693D02*
G03Y39370I0J3937D01*
G01X-175984D02*
G03Y31496I0J-3937D01*
G01X-214567Y43307D02*
Y1925197D01*
G01Y43307D02*
Y1925197D01*
G01Y149606D02*
Y43307D01*
G01Y149606D02*
Y43272D01*
G01Y1807087D02*
Y161417D01*
G01Y1807087D02*
Y161417D01*
G01Y1818898D02*
Y1925231D01*
G01Y1818898D02*
Y1925231D01*
G01X-210630Y1929134D02*
G03X-214567Y1925197I0J-3937D01*
G01X-210630Y1929134D02*
G03X-214567Y1925197I0J-3937D01*
G01X-210630Y1929134D02*
X-80709D01*
G01X-210630D02*
X-80709D01*
G01X-175984Y1937008D02*
G03Y1929134I0J-3937D01*
G01X-206693D02*
G03Y1937008I0J3937D01*
G01X-175984D02*
G03Y1929134I0J-3937D01*
G01X-206693D02*
G03Y1937008I0J3937D01*
G01X-175984D02*
X-84638D01*
G01X-214567D02*
X-206693D01*
G01X-84638Y1968504D02*
X-199567D01*
G01X-175984Y1937008D02*
X-84638D01*
G01X-214567D02*
X-206693D01*
G01X-76772Y3937D02*
G03X-72835Y0I3937J0D01*
G01X-76772Y35433D02*
G03X-80709Y39370I-3937J0D01*
G01X-76772Y35433D02*
G03X-80709Y39370I-3937J0D01*
G01X-76772Y3937D02*
G03X-72835Y0I3937J0D01*
G01X-11811D02*
X-72835D01*
G01X-11811D02*
X-72835D01*
G01X-76772Y3937D02*
Y35433D01*
G01Y3937D02*
Y35433D01*
G01X-72835Y0D02*
X-11811D01*
G01X-76772Y3937D02*
G03X-72835Y0I3937J0D01*
G01X-84646Y7874D02*
Y0D01*
G01X-76772Y7874D02*
G03X-84646I-3937J0D01*
G01Y31496D02*
G03X-76772I3937J0D01*
G01X-72835Y0D02*
X-11811D01*
G01X-76772Y3937D02*
G03X-72835Y0I3937J0D01*
G01X-84646Y7874D02*
Y0D01*
G01X-76772Y7874D02*
G03X-84646I-3937J0D01*
G01Y31496D02*
G03X-76772I3937J0D01*
G01X-80709Y1929134D02*
G03X-76772Y1933071I0J3937D01*
G01X-80709Y1929134D02*
G03X-76772Y1933071I0J3937D01*
G01D02*
Y1964567D01*
G01Y1933071D02*
Y1964567D01*
G01X-76763Y1937008D02*
G03X-84638I-3937J0D01*
G01X-72835Y1968504D02*
G03X-76772Y1964567I0J-3937D01*
G01X-72835Y1968504D02*
G03X-76772Y1964567I0J-3937D01*
G01X-72835Y1968504D02*
X-11811D01*
G01X-72835D02*
X-11811D01*
G01X-72835D02*
G03X-76772Y1964567I0J-3937D01*
G01X-11811Y1968504D02*
X-72835D01*
G01X-84638Y1960889D02*
Y1968504D01*
G01Y1960889D02*
G03X-76763I3938J0D01*
G01X-72835Y1968504D02*
G03X-76772Y1964567I0J-3937D01*
G01X-11811Y1968504D02*
X-72835D01*
G01X-84638Y1960889D02*
Y1968504D01*
G01Y1960889D02*
G03X-76763I3938J0D01*
G01X-14018Y-107763D02*
Y-90263D01*
X-8778D01*
X-7031Y-91138D01*
X-5721Y-93180D01*
X-5284Y-95513D01*
X-5721Y-97846D01*
X-6813Y-99596D01*
X-8778Y-100472D01*
X-14018D01*
G01X12652Y-91722D02*
X11342Y-90846D01*
X9814Y-90263D01*
X8067D01*
X6102Y-91138D01*
X4574Y-92596D01*
X3482Y-94347D01*
X2609Y-97263D01*
X2390Y-99888D01*
X2827Y-102513D01*
X3482Y-104263D01*
X4792Y-106013D01*
X6321Y-107180D01*
X7849Y-107763D01*
X9377D01*
X10906Y-107180D01*
X12216Y-106305D01*
X13308Y-105139D01*
G01X27095Y-98430D02*
X27969Y-97555D01*
X28624Y-96097D01*
X29061Y-94054D01*
X28624Y-92305D01*
X27751Y-91138D01*
X26222Y-90263D01*
X20327D01*
Y-107763D01*
X27532D01*
X29061Y-106597D01*
X29934Y-104846D01*
X30371Y-102805D01*
X29934Y-100763D01*
X28624Y-99013D01*
X27095Y-98430D01*
X20327D01*
G01X36299Y-113596D02*
X49399D01*
G01X55327Y-107763D02*
Y-90263D01*
X65371Y-107763D01*
Y-90263D01*
G01X77849Y-107763D02*
X76102Y-107471D01*
X74574Y-106305D01*
X73264Y-104555D01*
X72390Y-102513D01*
X71954Y-100180D01*
Y-97846D01*
X72390Y-95513D01*
X73264Y-93471D01*
X74574Y-91722D01*
X76102Y-90555D01*
X77849Y-90263D01*
X79595Y-90555D01*
X81124Y-91722D01*
X82434Y-93471D01*
X83308Y-95513D01*
X83744Y-97846D01*
Y-100180D01*
X83308Y-102513D01*
X82434Y-104555D01*
X81124Y-106305D01*
X79595Y-107471D01*
X77849Y-107763D01*
G01X-901Y-152763D02*
Y-135263D01*
X-3521Y-138763D01*
G01Y-152763D02*
X1719D01*
G01X12451Y-138180D02*
X13761Y-136430D01*
X15289Y-135555D01*
X17036Y-135263D01*
X19219Y-135846D01*
X20747Y-137305D01*
X21184Y-139054D01*
X20966Y-140805D01*
X20092Y-142263D01*
X15726Y-145180D01*
X13761Y-147221D01*
X12451Y-150139D01*
X12014Y-152763D01*
X21184D01*
G01X36719D02*
Y-135263D01*
X28640Y-147805D01*
X39558D01*
G01X46796Y-149263D02*
X48105Y-151305D01*
X49852Y-152471D01*
X51817Y-152763D01*
X53564Y-152471D01*
X55311Y-151013D01*
X56402Y-149263D01*
X56621Y-147513D01*
X56184Y-145472D01*
X54656Y-144013D01*
X53127Y-143430D01*
X51162D01*
G01X53127D02*
X54437Y-142555D01*
X55529Y-141097D01*
X55966Y-139347D01*
X55529Y-137596D01*
X54437Y-136138D01*
X52472Y-135263D01*
X50507Y-135555D01*
X48542Y-136722D01*
G01X64296Y-149263D02*
X65605Y-151305D01*
X67352Y-152471D01*
X69317Y-152763D01*
X71064Y-152471D01*
X72811Y-151013D01*
X73902Y-149263D01*
X74121Y-147513D01*
X73684Y-145472D01*
X72156Y-144013D01*
X70627Y-143430D01*
X68662D01*
G01X70627D02*
X71937Y-142555D01*
X73029Y-141097D01*
X73466Y-139347D01*
X73029Y-137596D01*
X71937Y-136138D01*
X69972Y-135263D01*
X68007Y-135555D01*
X66042Y-136722D01*
G01X-11811Y0D02*
G03X-7874Y3937I0J3937D01*
G01X-11811Y0D02*
G03X-7874Y3937I0J3937D01*
G01Y43110D02*
Y3937D01*
G01Y43110D02*
Y3937D01*
G01X0D02*
G03X3937Y0I3937J0D01*
G01X0Y3937D02*
G03X3937Y0I3937J0D01*
G01X0Y3937D02*
Y43110D01*
G01Y3937D02*
Y43110D01*
G01X64961Y0D02*
X3937D01*
G01X64961D02*
X3937D01*
G01X0Y3937D02*
G03X3937Y0I3937J0D01*
G01X0Y1964567D02*
Y3937D01*
G01X3937Y0D02*
X64961D01*
G01X-7874Y3937D02*
Y1964567D01*
G01X-11811Y0D02*
G03X-7874Y3937I0J3937D01*
G01X0Y11811D02*
G03X-7874I-3937J0D01*
G01Y42520D02*
G03X0I3937J0D01*
G01Y3937D02*
G03X3937Y0I3937J0D01*
G01X0Y1964567D02*
Y3937D01*
G01X3937Y0D02*
X64961D01*
G01X-7874Y3937D02*
Y1964567D01*
G01X-11811Y0D02*
G03X-7874Y3937I0J3937D01*
G01X0Y11811D02*
G03X-7874I-3937J0D01*
G01Y42520D02*
G03X0I3937J0D01*
G01X-7874Y93110D02*
Y43110D01*
G01Y93110D02*
Y43110D01*
G01X0D02*
Y93110D01*
G01Y43110D02*
Y93110D01*
G01X-7874Y214764D02*
Y93110D01*
G01Y214764D02*
Y93110D01*
G01X0D02*
Y214764D01*
G01Y93110D02*
Y214764D01*
G01X-7874Y226968D02*
Y214764D01*
G01Y226968D02*
Y214764D01*
G01Y342461D02*
Y226968D01*
G01Y342461D02*
Y226968D01*
G01X0Y226969D02*
Y342461D01*
G01Y226969D02*
Y342461D01*
G01Y214764D02*
Y226969D01*
G01Y214764D02*
Y226969D01*
G01Y278740D02*
G03X-7874I-3937J0D01*
G01X0D02*
G03X-7874I-3937J0D01*
G01Y354665D02*
Y342461D01*
G01Y354665D02*
Y342461D01*
G01X0D02*
Y354665D01*
G01Y342461D02*
Y354665D01*
G01X-7874Y309449D02*
G03X0I3937J0D01*
G01X-7874D02*
G03X0I3937J0D01*
G01X-7874Y476339D02*
Y354665D01*
G01Y476339D02*
Y354665D01*
G01X0D02*
Y476339D01*
G01Y354665D02*
Y476339D01*
G01X-7874Y526339D02*
Y476339D01*
G01Y526339D02*
Y476339D01*
G01X0D02*
Y526339D01*
G01Y476339D02*
Y526339D01*
G01X-7874Y736181D02*
Y526339D01*
G01Y736181D02*
Y526339D01*
G01X0D02*
Y736181D01*
G01Y526339D02*
Y736181D01*
G01Y545669D02*
G03X-7874I-3937J0D01*
G01X0D02*
G03X-7874I-3937J0D01*
G01Y576378D02*
G03X0I3937J0D01*
G01X-7874D02*
G03X0I3937J0D01*
G01X-7874Y786181D02*
Y736181D01*
G01Y786181D02*
Y736181D01*
G01X0D02*
Y786181D01*
G01Y736181D02*
Y786181D01*
G01X-7874Y907815D02*
Y786181D01*
G01Y907815D02*
Y786181D01*
G01X0D02*
Y907815D01*
G01Y786181D02*
Y907815D01*
G01X-7874Y862205D02*
G03X0I3937J0D01*
G01Y831496D02*
G03X-7874I-3937J0D01*
G01Y862205D02*
G03X0I3937J0D01*
G01Y831496D02*
G03X-7874I-3937J0D01*
G01Y920020D02*
Y907815D01*
G01Y920020D02*
Y907815D01*
G01X0D02*
Y920020D01*
G01Y907815D02*
Y920020D01*
G01X-7874Y1048484D02*
Y920020D01*
G01Y1048484D02*
Y920020D01*
G01X0D02*
Y1048484D01*
G01Y920020D02*
Y1048484D01*
G01X-7874Y1060689D02*
Y1048484D01*
G01Y1060689D02*
Y1048484D01*
G01Y1182323D02*
Y1060689D01*
G01Y1182323D02*
Y1060689D01*
G01X0D02*
Y1182323D01*
G01Y1060689D02*
Y1182323D01*
G01Y1048484D02*
Y1060689D01*
G01Y1048484D02*
Y1060689D01*
G01Y1106299D02*
G03X-7874I-3937J0D01*
G01X0D02*
G03X-7874I-3937J0D01*
G01Y1137008D02*
G03X0I3937J0D01*
G01X-7874D02*
G03X0I3937J0D01*
G01X-7874Y1232323D02*
Y1182323D01*
G01Y1232323D02*
Y1182323D01*
G01X0D02*
Y1232323D01*
G01Y1182323D02*
Y1232323D01*
G01X-7874Y1442165D02*
Y1232323D01*
G01Y1442165D02*
Y1232323D01*
G01X0D02*
Y1442165D01*
G01Y1232323D02*
Y1442165D01*
G01X-7874Y1422835D02*
G03X0I3937J0D01*
G01Y1392126D02*
G03X-7874I-3937J0D01*
G01Y1422835D02*
G03X0I3937J0D01*
G01Y1392126D02*
G03X-7874I-3937J0D01*
G01Y1492165D02*
Y1442165D01*
G01Y1492165D02*
Y1442165D01*
G01X0D02*
Y1492165D01*
G01Y1442165D02*
Y1492165D01*
G01X-7874Y1613839D02*
Y1492165D01*
G01Y1613839D02*
Y1492165D01*
G01X0D02*
Y1613839D01*
G01Y1492165D02*
Y1613839D01*
G01X-7874Y1626043D02*
Y1613839D01*
G01Y1626043D02*
Y1613839D01*
G01Y1741535D02*
Y1626043D01*
G01Y1741535D02*
Y1626043D01*
G01X0D02*
Y1741535D01*
G01Y1626043D02*
Y1741535D01*
G01Y1613839D02*
Y1626043D01*
G01Y1613839D02*
Y1626043D01*
G01Y1659055D02*
G03X-7874I-3937J0D01*
G01X0D02*
G03X-7874I-3937J0D01*
G01Y1689764D02*
G03X0I3937J0D01*
G01X-7874D02*
G03X0I3937J0D01*
G01X-7874Y1753740D02*
Y1741535D01*
G01Y1753740D02*
Y1741535D01*
G01Y1875394D02*
Y1753740D01*
G01Y1875394D02*
Y1753740D01*
G01X0D02*
Y1875394D01*
G01Y1753740D02*
Y1875394D01*
G01Y1741535D02*
Y1753740D01*
G01Y1741535D02*
Y1753740D01*
G01X-7874Y1925394D02*
Y1875394D01*
G01Y1925394D02*
Y1875394D01*
G01X0D02*
Y1925394D01*
G01Y1875394D02*
Y1925394D01*
G01X-7874Y1964567D02*
Y1925394D01*
G01Y1964567D02*
Y1925394D01*
G01X0D02*
Y1964567D01*
G01Y1925394D02*
Y1964567D01*
G01Y1925984D02*
G03X-7874I-3937J0D01*
G01X0D02*
G03X-7874I-3937J0D01*
G01Y1964567D02*
G03X-11811Y1968504I-3937J0D01*
G01X-7874Y1964567D02*
G03X-11811Y1968504I-3937J0D01*
G01X3937D02*
G03X0Y1964567I0J-3937D01*
G01X3937Y1968504D02*
G03X0Y1964567I0J-3937D01*
G01X3937Y1968504D02*
X64961D01*
G01X3937D02*
X64961D01*
G01X3937D02*
G03X0Y1964567I0J-3937D01*
G01X64961Y1968504D02*
X3937D01*
G01X-7874Y1964567D02*
G03X-11811Y1968504I-3937J0D01*
G01X-7874Y1956693D02*
G03X0I3937J0D01*
G01X3937Y1968504D02*
G03X0Y1964567I0J-3937D01*
G01X64961Y1968504D02*
X3937D01*
G01X-7874Y1964567D02*
G03X-11811Y1968504I-3937J0D01*
G01X-7874Y1956693D02*
G03X0I3937J0D01*
G01X168110Y31496D02*
X76763D01*
G01X72835Y39370D02*
G03X68898Y35433I0J-3937D01*
G01X72835Y39370D02*
G03X68898Y35433I0J-3937D01*
G01X64961Y0D02*
G03X68898Y3937I0J3937D01*
G01X64961Y0D02*
G03X68898Y3937I0J3937D01*
G01Y35433D02*
Y3937D01*
G01Y35433D02*
Y3937D01*
G01X202756Y39370D02*
X72835D01*
G01X202756D02*
X72835D01*
G01D02*
X202756D01*
G01X72835D02*
G03X68898Y35433I0J-3937D01*
G01Y3937D02*
Y35485D01*
G01X64961Y0D02*
G03X68898Y3937I0J3937D01*
G01X76763D02*
G03X80700Y0I3937J0D01*
G01X76763Y7615D02*
Y3937D01*
G01X80700Y0D02*
X340551D01*
G01X168110Y31496D02*
X76763D01*
G01Y7615D02*
G03X68889I-3937J0D01*
G01Y31496D02*
G03X76763I3937J0D01*
G01X72835Y39370D02*
X202756D01*
G01X72835D02*
G03X68898Y35433I0J-3937D01*
G01Y3937D02*
Y35485D01*
G01X64961Y0D02*
G03X68898Y3937I0J3937D01*
G01X76763D02*
G03X80700Y0I3937J0D01*
G01X76763Y7615D02*
Y3937D01*
G01X80700Y0D02*
X340551D01*
G01X168110Y31496D02*
X76763D01*
G01Y7615D02*
G03X68889I-3937J0D01*
G01Y31496D02*
G03X76763I3937J0D01*
G01X68898Y1933071D02*
G03X72835Y1929134I3937J0D01*
G01X68898Y1933071D02*
G03X72835Y1929134I3937J0D01*
G01D02*
X202756D01*
G01X72835D02*
X202756D01*
G01X68898Y1964567D02*
Y1933071D01*
G01Y1964567D02*
Y1933071D01*
G01D02*
Y1964567D01*
G01Y1933071D02*
G03X72835Y1929134I3937J0D01*
G01X202756D02*
X72835D01*
G01X68898Y1933071D02*
Y1964567D01*
G01Y1933071D02*
G03X72835Y1929134I3937J0D01*
G01X202756D02*
X72835D01*
G01X68898Y1964567D02*
G03X64961Y1968504I-3937J0D01*
G01X68898Y1964567D02*
G03X64961Y1968504I-3937J0D01*
G01X68898Y1964567D02*
G03X64961Y1968504I-3937J0D01*
G01X109377D02*
X80709D01*
G01D02*
G03X76772Y1964567I0J-3937D01*
G01Y1960630D02*
Y1964567D01*
G01X168110Y1937008D02*
X76772D01*
G01X68898Y1960630D02*
G03X76772I3937J0D01*
G01Y1937008D02*
G03X68898I-3937J0D01*
G01Y1964567D02*
G03X64961Y1968504I-3937J0D01*
G01X109377D02*
X80709D01*
G01D02*
G03X76772Y1964567I0J-3937D01*
G01Y1960630D02*
Y1964567D01*
G01X168110Y1937008D02*
X76772D01*
G01X68898Y1960630D02*
G03X76772I3937J0D01*
G01Y1937008D02*
G03X68898I-3937J0D01*
G01X128690Y-90263D02*
X134149Y-107763D01*
X139608Y-90263D01*
G01X156016Y-107763D02*
X147282D01*
Y-90263D01*
X156016D01*
G01X152522Y-98721D02*
X147282D01*
G01X164782Y-107763D02*
Y-90263D01*
X170241D01*
X171987Y-91138D01*
X173079Y-92305D01*
X173516Y-94638D01*
X173079Y-96972D01*
X171769Y-98430D01*
X170241Y-99305D01*
X164782D01*
G01X170241D02*
X173516Y-107763D01*
G01X186649Y-108346D02*
X186212Y-108055D01*
Y-107471D01*
X186649Y-107180D01*
X187086Y-107471D01*
Y-108055D01*
X186649Y-108346D01*
G01X118011Y1968504D02*
X142520D01*
G01X109377D02*
X110137D01*
G01D02*
G03X118011I3937J0D01*
G01X110137D02*
G03X118011I3937J0D01*
G01X147501Y-138180D02*
X148811Y-136430D01*
X150339Y-135555D01*
X152086Y-135263D01*
X154269Y-135846D01*
X155797Y-137305D01*
X156234Y-139054D01*
X156016Y-140805D01*
X155142Y-142263D01*
X150776Y-145180D01*
X148811Y-147221D01*
X147501Y-150139D01*
X147064Y-152763D01*
X156234D01*
G01X163690D02*
X169149Y-135263D01*
X174608Y-152763D01*
G01X172642Y-146638D02*
X165655D01*
G01X168110Y31496D02*
G03Y39370I0J3937D01*
G01Y31496D02*
G03Y39370I0J3937D01*
G01Y1929134D02*
G03Y1937008I0J3937D01*
G01Y1929134D02*
G03Y1937008I0J3937D01*
G01X340559Y1968504D02*
X142520D01*
G01X340559D02*
X142520D01*
G01X202756Y39370D02*
G03X206693Y43307I0J3937D01*
G01X202756Y39370D02*
G03X206693Y43307I0J3937D01*
G01X202756Y39370D02*
G03X206693Y43307I0J3937D01*
G01X218504Y39370D02*
X348425D01*
G01X214567Y43307D02*
G03X218504Y39370I3937J0D01*
G01X222441Y31496D02*
X198819D01*
G01X222441D02*
G03Y39370I0J3937D01*
G01X198819D02*
G03Y31496I0J-3937D01*
G01X202756Y39370D02*
G03X206693Y43307I0J3937D01*
G01X218504Y39370D02*
X348425D01*
G01X214567Y43307D02*
G03X218504Y39370I3937J0D01*
G01X222441Y31496D02*
X198819D01*
G01X222441D02*
G03Y39370I0J3937D01*
G01X198819D02*
G03Y31496I0J-3937D01*
G01X214567Y161417D02*
Y43307D01*
G01X206693Y1925197D02*
Y43307D01*
G01Y1925197D02*
Y43307D01*
G01Y161417D02*
Y1807087D01*
G01X214567D02*
Y161417D01*
G01Y169291D02*
G03X206693I-3937J0D01*
G01Y161417D02*
Y1807087D01*
G01X214567D02*
Y161417D01*
G01Y169291D02*
G03X206693I-3937J0D01*
G01Y200000D02*
G03X214567I3937J0D01*
G01X206693D02*
G03X214567I3937J0D01*
G01Y436220D02*
G03X206693I-3937J0D01*
G01X214567D02*
G03X206693I-3937J0D01*
G01Y466929D02*
G03X214567I3937J0D01*
G01X206693D02*
G03X214567I3937J0D01*
G01Y703149D02*
G03X206693I-3937J0D01*
G01X214567D02*
G03X206693I-3937J0D01*
G01Y733858D02*
G03X214567I3937J0D01*
G01X206693D02*
G03X214567I3937J0D01*
G01Y970867D02*
G03X206693I-3937J0D01*
G01Y997637D02*
G03X214567I3937J0D01*
G01Y970867D02*
G03X206693I-3937J0D01*
G01Y997637D02*
G03X214567I3937J0D01*
G01X206693Y1265355D02*
G03X214567I3937J0D01*
G01Y1234646D02*
G03X206693I-3937J0D01*
G01Y1265355D02*
G03X214567I3937J0D01*
G01Y1234646D02*
G03X206693I-3937J0D01*
G01X214567Y1501575D02*
G03X206693I-3937J0D01*
G01X214567D02*
G03X206693I-3937J0D01*
G01Y1532284D02*
G03X214567I3937J0D01*
G01X206693D02*
G03X214567I3937J0D01*
G01Y1768504D02*
G03X206693I-3937J0D01*
G01X214567D02*
G03X206693I-3937J0D01*
G01X214567Y1807087D02*
Y1925197D01*
G01X206693Y1799213D02*
G03X214567I3937J0D01*
G01X206693D02*
G03X214567I3937J0D01*
G01X206693Y1925197D02*
G03X202756Y1929134I-3937J0D01*
G01X206693Y1925197D02*
G03X202756Y1929134I-3937J0D01*
G01X206693Y1925197D02*
G03X202756Y1929134I-3937J0D01*
G01X218504D02*
G03X214567Y1925197I0J-3937D01*
G01X348425Y1929134D02*
X218504D01*
G01X198819Y1937008D02*
G03Y1929134I0J-3937D01*
G01X222441D02*
G03Y1937008I0J3937D01*
G01X206693Y1925197D02*
G03X202756Y1929134I-3937J0D01*
G01X218504D02*
G03X214567Y1925197I0J-3937D01*
G01X348425Y1929134D02*
X218504D01*
G01X198819Y1937008D02*
G03Y1929134I0J-3937D01*
G01X222441D02*
G03Y1937008I0J3937D01*
G01X198819D02*
X222441D01*
G01X198819D02*
X222441D01*
G01X253482Y-90263D02*
Y-107763D01*
X262216D01*
G01X279279D02*
Y-96097D01*
G01Y-98138D02*
X278406Y-96972D01*
X277095Y-96388D01*
X275567Y-96097D01*
X274039Y-96680D01*
X272729Y-97846D01*
X271855Y-99596D01*
X271419Y-101930D01*
X271855Y-104263D01*
X272729Y-106013D01*
X274039Y-107180D01*
X275567Y-107763D01*
X277095Y-107471D01*
X278406Y-106597D01*
X279279Y-105430D01*
G01X288264Y-113013D02*
X289574Y-113596D01*
X291321Y-113013D01*
X292412Y-111847D01*
X293286Y-110388D01*
X294595Y-105722D01*
X297434Y-96097D01*
G01X290447D02*
X294595Y-105722D01*
G01X307074Y-99888D02*
X314061D01*
X313406Y-97846D01*
X312314Y-96680D01*
X310786Y-96097D01*
X309257Y-96388D01*
X307947Y-97263D01*
X307074Y-99305D01*
X306637Y-101055D01*
Y-102805D01*
X307074Y-104555D01*
X308166Y-106305D01*
X309476Y-107471D01*
X311004Y-107763D01*
X312532Y-107180D01*
X314061Y-105430D01*
G01X324792Y-107763D02*
Y-96097D01*
G01Y-98430D02*
X325884Y-97263D01*
X326976Y-96388D01*
X328504Y-96097D01*
X329595Y-96388D01*
X330906Y-97263D01*
G01X342074Y-105722D02*
X343166Y-106888D01*
X344694Y-107763D01*
X346004D01*
X347314Y-107180D01*
X348187Y-106305D01*
X348624Y-105139D01*
X348406Y-103388D01*
X347532Y-102513D01*
X343602Y-100763D01*
X342729Y-98721D01*
X343166Y-97263D01*
X344039Y-96388D01*
X345349Y-96097D01*
X346659Y-96388D01*
X347969Y-97263D01*
G01X261796Y-152763D02*
Y-135263D01*
X266162D01*
X267909Y-136138D01*
X269219Y-137305D01*
X270311Y-139054D01*
X271184Y-141097D01*
X271402Y-144013D01*
X271184Y-146930D01*
X270311Y-148972D01*
X269219Y-150722D01*
X267909Y-151888D01*
X266162Y-152763D01*
X261796D01*
G01X279732D02*
Y-135263D01*
X285191D01*
X286937Y-136138D01*
X288029Y-137305D01*
X288466Y-139638D01*
X288029Y-141972D01*
X286719Y-143430D01*
X285191Y-144305D01*
X279732D01*
G01X285191D02*
X288466Y-152763D01*
G01X298979Y-135263D02*
X304219D01*
G01X301599D02*
Y-152763D01*
G01X298979D02*
X304219D01*
G01X314732Y-135263D02*
Y-152763D01*
X323466D01*
G01X332232Y-135263D02*
Y-152763D01*
X340966D01*
G01X253150Y31496D02*
X344488D01*
G01X253150Y39370D02*
G03Y31496I0J-3937D01*
G01D02*
X344488D01*
G01X253150Y39370D02*
G03Y31496I0J-3937D01*
G01Y1937008D02*
G03Y1929134I0J-3937D01*
G01Y1937008D02*
G03Y1929134I0J-3937D01*
G01Y1937008D02*
X344496D01*
G01X253150D02*
X344496D01*
G01X340551Y0D02*
G03X344488Y3937I0J3937D01*
G01X340551Y0D02*
G03X344488Y3937I0J3937D01*
G01X344496Y1964567D02*
G03X340559Y1968504I-3937J0D01*
G01X344496Y1964567D02*
G03X340559Y1968504I-3937J0D01*
G01X356299Y0D02*
X417323D01*
G01X352362Y3937D02*
G03X356299Y0I3937J0D01*
G01X352362Y35433D02*
Y3937D01*
G01Y35433D02*
G03X348425Y39370I-3937J0D01*
G01X344488Y7874D02*
Y3937D01*
G01X352362Y7874D02*
G03X344488I-3937J0D01*
G01Y31496D02*
G03X352362I3937J0D01*
G01X356299Y0D02*
X417323D01*
G01X352362Y3937D02*
G03X356299Y0I3937J0D01*
G01X352362Y35433D02*
Y3937D01*
G01Y35433D02*
G03X348425Y39370I-3937J0D01*
G01X344488Y7874D02*
Y3937D01*
G01X352362Y7874D02*
G03X344488I-3937J0D01*
G01Y31496D02*
G03X352362I3937J0D01*
G01X348425Y1929134D02*
G03X352362Y1933071I0J3937D01*
G01Y1964567D02*
Y1933071D01*
G01X348425Y1929134D02*
G03X352362Y1933071I0J3937D01*
G01Y1964567D02*
Y1933071D01*
G01X356299Y1968504D02*
G03X352362Y1964567I0J-3937D01*
G01X417323Y1968504D02*
X356299D01*
G01X344496Y1960889D02*
Y1964567D01*
G01Y1960889D02*
G03X352370I3937J0D01*
G01Y1937008D02*
G03X344496I-3937J0D01*
G01X356299Y1968504D02*
G03X352362Y1964567I0J-3937D01*
G01X417323Y1968504D02*
X356299D01*
G01X344496Y1960889D02*
Y1964567D01*
G01Y1960889D02*
G03X352370I3937J0D01*
G01Y1937008D02*
G03X344496I-3937J0D01*
G01X404346Y-107763D02*
Y-90263D01*
X408712D01*
X410459Y-91138D01*
X411769Y-92305D01*
X412861Y-94054D01*
X413734Y-96097D01*
X413952Y-99013D01*
X413734Y-101930D01*
X412861Y-103972D01*
X411769Y-105722D01*
X410459Y-106888D01*
X408712Y-107763D01*
X404346D01*
G01X423374Y-99888D02*
X430361D01*
X429706Y-97846D01*
X428614Y-96680D01*
X427086Y-96097D01*
X425557Y-96388D01*
X424247Y-97263D01*
X423374Y-99305D01*
X422937Y-101055D01*
Y-102805D01*
X423374Y-104555D01*
X424466Y-106305D01*
X425776Y-107471D01*
X427304Y-107763D01*
X428832Y-107180D01*
X430361Y-105430D01*
G01X440874Y-105722D02*
X441966Y-106888D01*
X443494Y-107763D01*
X444804D01*
X446114Y-107180D01*
X446987Y-106305D01*
X447424Y-105139D01*
X447206Y-103388D01*
X446332Y-102513D01*
X442402Y-100763D01*
X441529Y-98721D01*
X441966Y-97263D01*
X442839Y-96388D01*
X444149Y-96097D01*
X445459Y-96388D01*
X446769Y-97263D01*
G01X461649Y-96097D02*
Y-107763D01*
G01Y-91430D02*
X461212Y-91138D01*
Y-90555D01*
X461649Y-90263D01*
X462086Y-90555D01*
Y-91138D01*
X461649Y-91430D01*
G01X476092Y-112138D02*
X477621Y-113305D01*
X479367Y-113596D01*
X480895Y-113305D01*
X482206Y-111847D01*
X483079Y-109805D01*
Y-96097D01*
G01Y-98430D02*
X482206Y-97263D01*
X480895Y-96388D01*
X479367Y-96097D01*
X477621Y-96680D01*
X476529Y-97846D01*
X475655Y-99888D01*
X475219Y-101930D01*
X475437Y-103680D01*
X476311Y-105722D01*
X477621Y-107180D01*
X479367Y-107763D01*
X480677Y-107471D01*
X482206Y-106305D01*
X483079Y-105139D01*
G01X492937Y-107763D02*
Y-96097D01*
G01Y-99013D02*
X493811Y-97555D01*
X495121Y-96388D01*
X496867Y-96097D01*
X498395Y-96388D01*
X499706Y-97555D01*
X500361Y-99596D01*
Y-107763D01*
G01X510874Y-99888D02*
X517861D01*
X517206Y-97846D01*
X516114Y-96680D01*
X514586Y-96097D01*
X513057Y-96388D01*
X511747Y-97263D01*
X510874Y-99305D01*
X510437Y-101055D01*
Y-102805D01*
X510874Y-104555D01*
X511966Y-106305D01*
X513276Y-107471D01*
X514804Y-107763D01*
X516332Y-107180D01*
X517861Y-105430D01*
G01X528592Y-107763D02*
Y-96097D01*
G01Y-98430D02*
X529684Y-97263D01*
X530776Y-96388D01*
X532304Y-96097D01*
X533395Y-96388D01*
X534706Y-97263D01*
G01X429722Y-152763D02*
Y-135263D01*
X435399Y-149846D01*
X441076Y-135263D01*
Y-152763D01*
G01X452899D02*
X451152Y-152471D01*
X449624Y-151305D01*
X448314Y-149555D01*
X447440Y-147513D01*
X447004Y-145180D01*
Y-142846D01*
X447440Y-140513D01*
X448314Y-138471D01*
X449624Y-136722D01*
X451152Y-135555D01*
X452899Y-135263D01*
X454645Y-135555D01*
X456174Y-136722D01*
X457484Y-138471D01*
X458358Y-140513D01*
X458794Y-142846D01*
Y-145180D01*
X458358Y-147513D01*
X457484Y-149555D01*
X456174Y-151305D01*
X454645Y-152471D01*
X452899Y-152763D01*
G01X465814Y-150430D02*
X467561Y-151888D01*
X469526Y-152763D01*
X471272D01*
X473019Y-151888D01*
X474329Y-150430D01*
X474984Y-148388D01*
X474547Y-146347D01*
X473456Y-144596D01*
X471491Y-143430D01*
X468871Y-142846D01*
X467342Y-141680D01*
X466687Y-139638D01*
X467124Y-137596D01*
X468216Y-136138D01*
X469744Y-135263D01*
X471272D01*
X472801Y-135846D01*
X474111Y-137305D01*
G01X483314Y-150430D02*
X485061Y-151888D01*
X487026Y-152763D01*
X488772D01*
X490519Y-151888D01*
X491829Y-150430D01*
X492484Y-148388D01*
X492047Y-146347D01*
X490956Y-144596D01*
X488991Y-143430D01*
X486371Y-142846D01*
X484842Y-141680D01*
X484187Y-139638D01*
X484624Y-137596D01*
X485716Y-136138D01*
X487244Y-135263D01*
X488772D01*
X490301Y-135846D01*
X491611Y-137305D01*
G01X509766Y-152763D02*
X501032D01*
Y-135263D01*
X509766D01*
G01X506272Y-143721D02*
X501032D01*
G01X429134Y3937D02*
G03X433071Y0I3937J0D01*
G01X429134Y1964567D02*
Y3937D01*
G01X433071Y0D02*
X494095D01*
G01X421260Y3937D02*
Y1964567D01*
G01X417323Y0D02*
G03X421260Y3937I0J3937D01*
G01X429134Y11811D02*
G03X421260I-3937J0D01*
G01Y42520D02*
G03X429134I3937J0D01*
G01Y3937D02*
G03X433071Y0I3937J0D01*
G01X429134Y1964567D02*
Y3937D01*
G01X433071Y0D02*
X494095D01*
G01X421260Y3937D02*
Y1964567D01*
G01X417323Y0D02*
G03X421260Y3937I0J3937D01*
G01X429134Y11811D02*
G03X421260I-3937J0D01*
G01Y42520D02*
G03X429134I3937J0D01*
G01Y278740D02*
G03X421260I-3937J0D01*
G01X429134D02*
G03X421260I-3937J0D01*
G01Y309449D02*
G03X429134I3937J0D01*
G01X421260D02*
G03X429134I3937J0D01*
G01Y545669D02*
G03X421260I-3937J0D01*
G01X429134D02*
G03X421260I-3937J0D01*
G01Y576378D02*
G03X429134I3937J0D01*
G01X421260D02*
G03X429134I3937J0D01*
G01X421260Y862205D02*
G03X429134I3937J0D01*
G01Y831496D02*
G03X421260I-3937J0D01*
G01Y862205D02*
G03X429134I3937J0D01*
G01Y831496D02*
G03X421260I-3937J0D01*
G01X429134Y1106299D02*
G03X421260I-3937J0D01*
G01X429134D02*
G03X421260I-3937J0D01*
G01Y1137008D02*
G03X429134I3937J0D01*
G01X421260D02*
G03X429134I3937J0D01*
G01X421260Y1422835D02*
G03X429134I3937J0D01*
G01Y1392126D02*
G03X421260I-3937J0D01*
G01Y1422835D02*
G03X429134I3937J0D01*
G01Y1392126D02*
G03X421260I-3937J0D01*
G01X429134Y1659055D02*
G03X421260I-3937J0D01*
G01X429134D02*
G03X421260I-3937J0D01*
G01Y1689764D02*
G03X429134I3937J0D01*
G01X421260D02*
G03X429134I3937J0D01*
G01Y1925984D02*
G03X421260I-3937J0D01*
G01X429134D02*
G03X421260I-3937J0D01*
G01X433071Y1968504D02*
G03X429134Y1964567I0J-3937D01*
G01X494095Y1968504D02*
X433071D01*
G01X421260Y1964567D02*
G03X417323Y1968504I-3937J0D01*
G01X421260Y1956693D02*
G03X429134I3937J0D01*
G01X433071Y1968504D02*
G03X429134Y1964567I0J-3937D01*
G01X494095Y1968504D02*
X433071D01*
G01X421260Y1964567D02*
G03X417323Y1968504I-3937J0D01*
G01X421260Y1956693D02*
G03X429134I3937J0D01*
G01X433071Y1968504D02*
G03X429134Y1964567I0J-3937D01*
G01X421260D02*
G03X417323Y1968504I-3937J0D01*
G01X494095Y0D02*
G03X498032Y3937I0J3937D01*
G01X494095Y0D02*
G03X498032Y3937I0J3937D01*
G01Y1964567D02*
G03X494095Y1968504I-3937J0D01*
G01X498032Y1964567D02*
G03X494095Y1968504I-3937J0D01*
G01X501969Y39370D02*
X631890D01*
G01X501969D02*
G03X498032Y35433I0J-3937D01*
G01Y3937D02*
Y35433D01*
G01X505897Y0D02*
X648386D01*
G01X505897Y7615D02*
Y0D01*
G01X597244Y31496D02*
X505897D01*
G01Y7615D02*
G03X498023I-3937J0D01*
G01Y31496D02*
G03X505897I3937J0D01*
G01X501969Y39370D02*
X631890D01*
G01X501969D02*
G03X498032Y35433I0J-3937D01*
G01Y3937D02*
Y35433D01*
G01X505897Y0D02*
X620827D01*
G01X505897Y7615D02*
Y0D01*
G01X597244Y31496D02*
X505897D01*
G01Y7615D02*
G03X498023I-3937J0D01*
G01Y31496D02*
G03X505897I3937J0D01*
G01X498032Y1933071D02*
Y1960630D01*
G01Y1933071D02*
G03X501969Y1929134I3937J0D01*
G01X631890D02*
X501969D01*
G01X498032Y1933071D02*
Y1964567D01*
G01Y1933071D02*
G03X501969Y1929134I3937J0D01*
G01X631890D02*
X501969D01*
G01X505906Y1960630D02*
Y1968504D01*
G01D02*
X648386D01*
G01X597244Y1937008D02*
X505906D01*
G01X498032Y1960630D02*
G03X505906I3937J0D01*
G01Y1937008D02*
G03X498032I-3937J0D01*
G01X505906Y1960630D02*
Y1968504D01*
G01D02*
X620827D01*
G01X597244Y1937008D02*
X505906D01*
G01X498032Y1960630D02*
G03X505906I3937J0D01*
G01Y1937008D02*
G03X498032I-3937J0D01*
G01X575349Y-152763D02*
Y-135263D01*
X572729Y-138763D01*
G01Y-152763D02*
X577969D01*
G01X588701Y-138180D02*
X590011Y-136430D01*
X591539Y-135555D01*
X593286Y-135263D01*
X595469Y-135846D01*
X596997Y-137305D01*
X597434Y-139054D01*
X597216Y-140805D01*
X596342Y-142263D01*
X591976Y-145180D01*
X590011Y-147221D01*
X588701Y-150139D01*
X588264Y-152763D01*
X597434D01*
G01X606419Y-153346D02*
X614279Y-135263D01*
G01X627849Y-152763D02*
Y-135263D01*
X625229Y-138763D01*
G01Y-152763D02*
X630469D01*
G01X645349D02*
Y-135263D01*
X642729Y-138763D01*
G01Y-152763D02*
X647969D01*
G01X658919Y-153346D02*
X666779Y-135263D01*
G01X676201Y-138180D02*
X677511Y-136430D01*
X679039Y-135555D01*
X680786Y-135263D01*
X682969Y-135846D01*
X684497Y-137305D01*
X684934Y-139054D01*
X684716Y-140805D01*
X683842Y-142263D01*
X679476Y-145180D01*
X677511Y-147221D01*
X676201Y-150139D01*
X675764Y-152763D01*
X684934D01*
G01X697849Y-135263D02*
X696102Y-135846D01*
X694792Y-137305D01*
X693919Y-139054D01*
X693264Y-141388D01*
X693046Y-144013D01*
X693264Y-146638D01*
X693919Y-148972D01*
X694792Y-150722D01*
X696102Y-152180D01*
X697849Y-152763D01*
X699595Y-152180D01*
X700906Y-150722D01*
X701779Y-148972D01*
X702434Y-146638D01*
X702652Y-144013D01*
X702434Y-141388D01*
X701779Y-139054D01*
X700906Y-137305D01*
X699595Y-135846D01*
X697849Y-135263D01*
G01X715349Y-152763D02*
Y-135263D01*
X712729Y-138763D01*
G01Y-152763D02*
X717969D01*
G01X728046Y-150139D02*
X729355Y-151597D01*
X730884Y-152471D01*
X732849Y-152763D01*
X734814Y-152180D01*
X736342Y-151013D01*
X737434Y-148972D01*
X737652Y-146638D01*
X737216Y-144305D01*
X736124Y-142846D01*
X734595Y-141680D01*
X733067Y-141388D01*
X731539Y-141680D01*
X729574Y-142846D01*
X730229Y-135263D01*
X736124D01*
G01X623046Y-107763D02*
Y-90263D01*
X627412D01*
X629159Y-91138D01*
X630469Y-92305D01*
X631561Y-94054D01*
X632434Y-96097D01*
X632652Y-99013D01*
X632434Y-101930D01*
X631561Y-103972D01*
X630469Y-105722D01*
X629159Y-106888D01*
X627412Y-107763D01*
X623046D01*
G01X649279D02*
Y-96097D01*
G01Y-98138D02*
X648406Y-96972D01*
X647095Y-96388D01*
X645567Y-96097D01*
X644039Y-96680D01*
X642729Y-97846D01*
X641855Y-99596D01*
X641419Y-101930D01*
X641855Y-104263D01*
X642729Y-106013D01*
X644039Y-107180D01*
X645567Y-107763D01*
X647095Y-107471D01*
X648406Y-106597D01*
X649279Y-105430D01*
G01X662849Y-90263D02*
Y-107763D01*
G01X659792Y-96097D02*
X665906D01*
G01X677074Y-99888D02*
X684061D01*
X683406Y-97846D01*
X682314Y-96680D01*
X680786Y-96097D01*
X679257Y-96388D01*
X677947Y-97263D01*
X677074Y-99305D01*
X676637Y-101055D01*
Y-102805D01*
X677074Y-104555D01*
X678166Y-106305D01*
X679476Y-107471D01*
X681004Y-107763D01*
X682532Y-107180D01*
X684061Y-105430D01*
G01X643701Y169256D02*
Y39370D01*
G01X635827Y31496D02*
G03X643701Y39370I0J7874D01*
G01X650689Y19685D02*
G03I-6988J0D01*
G01X631890Y39370D02*
G03X635827Y43307I0J3937D01*
G01Y31496D02*
X627953D01*
G01X597244D02*
G03Y39370I0J3937D01*
G01X627953D02*
G03Y31496I0J-3937D01*
G01X650689Y19685D02*
G03I-6988J0D01*
G01X631890Y39370D02*
G03X635827Y43307I0J3937D01*
G01Y31496D02*
X627953D01*
G01X597244D02*
G03Y39370I0J3937D01*
G01X627953D02*
G03Y31496I0J-3937D01*
G01X635827Y161417D02*
Y43307D01*
G01X643701Y169256D02*
G03X635827I-3937J0D01*
G01X643701D02*
G03X635827I-3937J0D01*
G01Y161417D02*
Y1807087D01*
G01Y161417D02*
Y1807087D01*
G01X643701Y436186D02*
Y199965D01*
G01X635827D02*
G03X643701I3937J0D01*
G01X635827D02*
G03X643701I3937J0D01*
G01Y436186D02*
G03X635827I-3937J0D01*
G01X643701D02*
G03X635827I-3937J0D01*
G01X643701Y703115D02*
Y466894D01*
G01X635827D02*
G03X643701I3937J0D01*
G01X635827D02*
G03X643701I3937J0D01*
G01Y703115D02*
G03X635827I-3937J0D01*
G01X643701D02*
G03X635827I-3937J0D01*
G01X643701Y970832D02*
Y733823D01*
G01X635827D02*
G03X643701I3937J0D01*
G01X635827D02*
G03X643701I3937J0D01*
G01Y1234611D02*
Y997603D01*
G01X635827D02*
G03X643701I3937J0D01*
G01Y970832D02*
G03X635827I-3937J0D01*
G01Y997603D02*
G03X643701I3937J0D01*
G01Y970832D02*
G03X635827I-3937J0D01*
G01X643701Y1501541D02*
Y1265320D01*
G01X635827D02*
G03X643701I3937J0D01*
G01Y1234611D02*
G03X635827I-3937J0D01*
G01Y1265320D02*
G03X643701I3937J0D01*
G01Y1234611D02*
G03X635827I-3937J0D01*
G01X643701Y1501541D02*
G03X635827I-3937J0D01*
G01X643701D02*
G03X635827I-3937J0D01*
G01X643701Y1768470D02*
Y1532249D01*
G01X635827D02*
G03X643701I3937J0D01*
G01X635827D02*
G03X643701I3937J0D01*
G01Y1768470D02*
G03X635827I-3937J0D01*
G01X643701D02*
G03X635827I-3937J0D01*
G01Y1799178D02*
G03X643701I3937J0D01*
G01X635827D02*
G03X643701I3937J0D01*
G01Y1929134D02*
Y1799178D01*
G01X635827Y1818898D02*
Y1807087D01*
G01Y1818898D02*
Y1925197D01*
G01Y1818898D02*
Y1925197D01*
G01X643701Y1929134D02*
G03X635827Y1937008I-7874J0D01*
G01Y1925197D02*
G03X631890Y1929134I-3937J0D01*
G01X627953Y1937008D02*
G03Y1929134I0J-3937D01*
G01X597244D02*
G03Y1937008I0J3937D01*
G01X635827Y1925197D02*
G03X631890Y1929134I-3937J0D01*
G01X627953Y1937008D02*
G03Y1929134I0J-3937D01*
G01X597244D02*
G03Y1937008I0J3937D01*
G01X650689Y1948819D02*
G03I-6988J0D01*
G01X627953Y1937008D02*
X635827D01*
G01X650689Y1948819D02*
G03I-6988J0D01*
G01X627953Y1937008D02*
X635827D01*
G01X650689Y1948819D02*
G03I-6988J0D01*
G01X648386Y0D02*
G03X663386Y15000I0J15000D01*
G01Y1953504D02*
Y15000D01*
G01Y1953504D02*
G03X648386Y1968504I-15000J0D01*
G01X778000Y55000D02*
Y501500D01*
X1261600D01*
Y55000D01*
X778000D01*
G01Y83100D02*
X1261600D01*
G01X778000Y139300D02*
X1261600D01*
G01X778000Y111200D02*
X1261600D01*
G01X778000Y167400D02*
X1261600D01*
G01X778000Y223600D02*
X1261600D01*
G01X778000Y195500D02*
X1261600D01*
G01X778000Y279800D02*
X1261600D01*
G01X778000Y251700D02*
X1261600D01*
G01X778000Y336000D02*
X1261600D01*
G01X778000Y307900D02*
X1261600D01*
G01X778000Y392200D02*
X1261600D01*
G01X778000Y364100D02*
X1261600D01*
G01X789005Y429650D02*
Y442150D01*
X794895D01*
G01X792725Y436108D02*
X789005D01*
G01X802490Y442150D02*
X806210D01*
G01X804350D02*
Y429650D01*
G01X802490D02*
X806210D01*
G01X817680Y435900D02*
X820780D01*
Y432150D01*
X819850Y430900D01*
X818765Y430067D01*
X817215Y429650D01*
X815665Y430067D01*
X814580Y430900D01*
X813650Y432150D01*
X813030Y433608D01*
X812720Y435275D01*
Y436733D01*
X813030Y437983D01*
X813650Y439442D01*
X814580Y440692D01*
X815510Y441525D01*
X816750Y442150D01*
X817835D01*
X819075Y441733D01*
X820005Y440900D01*
G01X825740Y442150D02*
Y433192D01*
X826360Y431316D01*
X827600Y430067D01*
X829150Y429650D01*
X830700Y430067D01*
X831940Y431316D01*
X832560Y433192D01*
Y442150D01*
G01X838450Y429650D02*
Y442150D01*
X842325D01*
X843565Y441525D01*
X844340Y440692D01*
X844650Y439025D01*
X844340Y437358D01*
X843410Y436317D01*
X842325Y435692D01*
X838450D01*
G01X842325D02*
X844650Y429650D01*
G01X857050D02*
X850850D01*
Y442150D01*
X857050D01*
G01X854570Y436108D02*
X850850D01*
G01X778000Y448400D02*
X1261600D01*
G01X778000Y420300D02*
X1261600D01*
G01X778000Y476500D02*
X1261600D01*
G01X867900Y448400D02*
Y55000D01*
G01X861390Y482750D02*
Y495250D01*
X864490D01*
X865730Y494625D01*
X866660Y493792D01*
X867435Y492542D01*
X868055Y491083D01*
X868210Y489000D01*
X868055Y486917D01*
X867435Y485458D01*
X866660Y484208D01*
X865730Y483375D01*
X864490Y482750D01*
X861390D01*
G01X874100D02*
Y495250D01*
X877975D01*
X879215Y494625D01*
X879990Y493792D01*
X880300Y492125D01*
X879990Y490458D01*
X879060Y489417D01*
X877975Y488792D01*
X874100D01*
G01X877975D02*
X880300Y482750D01*
G01X887740Y495250D02*
X891460D01*
G01X889600D02*
Y482750D01*
G01X887740D02*
X891460D01*
G01X898900Y495250D02*
Y482750D01*
X905100D01*
G01X911300Y495250D02*
Y482750D01*
X917500D01*
G01X942610Y494208D02*
X941680Y494833D01*
X940595Y495250D01*
X939355D01*
X937960Y494625D01*
X936875Y493583D01*
X936100Y492333D01*
X935480Y490250D01*
X935325Y488375D01*
X935635Y486500D01*
X936100Y485250D01*
X937030Y484000D01*
X938115Y483167D01*
X939200Y482750D01*
X940285D01*
X941370Y483167D01*
X942300Y483791D01*
X943075Y484625D01*
G01X948345Y482750D02*
Y495250D01*
G01X954855D02*
Y482750D01*
G01Y489000D02*
X948345D01*
G01X960125Y482750D02*
X964000Y495250D01*
X967875Y482750D01*
G01X966480Y487125D02*
X961520D01*
G01X973300Y482750D02*
Y495250D01*
X977175D01*
X978415Y494625D01*
X979190Y493792D01*
X979500Y492125D01*
X979190Y490458D01*
X978260Y489417D01*
X977175Y488792D01*
X973300D01*
G01X977175D02*
X979500Y482750D01*
G01X988800Y495250D02*
Y482750D01*
G01X985235Y495250D02*
X992365D01*
G01X1001200Y482333D02*
X1000890Y482542D01*
Y482958D01*
X1001200Y483167D01*
X1001510Y482958D01*
Y482542D01*
X1001200Y482333D01*
G01Y487958D02*
X1000890Y488167D01*
Y488583D01*
X1001200Y488792D01*
X1001510Y488583D01*
Y488167D01*
X1001200Y487958D01*
G01X1026000Y495250D02*
Y482750D01*
G01X1022435Y495250D02*
X1029565D01*
G01X1038400Y482750D02*
X1037160Y482958D01*
X1036075Y483791D01*
X1035145Y485042D01*
X1034525Y486500D01*
X1034215Y488167D01*
Y489833D01*
X1034525Y491500D01*
X1035145Y492958D01*
X1036075Y494208D01*
X1037160Y495042D01*
X1038400Y495250D01*
X1039640Y495042D01*
X1040725Y494208D01*
X1041655Y492958D01*
X1042275Y491500D01*
X1042585Y489833D01*
Y488167D01*
X1042275Y486500D01*
X1041655Y485042D01*
X1040725Y483791D01*
X1039640Y482958D01*
X1038400Y482750D01*
G01X1047700D02*
Y495250D01*
X1051420D01*
X1052660Y494625D01*
X1053590Y493167D01*
X1053900Y491500D01*
X1053590Y489833D01*
X1052815Y488583D01*
X1051420Y487958D01*
X1047700D01*
G01X1075600Y495250D02*
Y482750D01*
G01X1073430Y491083D02*
X1077770D01*
G01X1088000Y482750D02*
X1087070Y482958D01*
X1086140Y483791D01*
X1085520Y485250D01*
X1085210Y486917D01*
X1085520Y488583D01*
X1086140Y490042D01*
X1087070Y490875D01*
X1088000Y491083D01*
X1088930Y490875D01*
X1089860Y490042D01*
X1090480Y488583D01*
X1090635Y486917D01*
X1090480Y485250D01*
X1089860Y483791D01*
X1088930Y482958D01*
X1088000Y482750D01*
G01X1114040Y489417D02*
X1114660Y490042D01*
X1115125Y491083D01*
X1115435Y492542D01*
X1115125Y493792D01*
X1114505Y494625D01*
X1113420Y495250D01*
X1109235D01*
Y482750D01*
X1114350D01*
X1115435Y483583D01*
X1116055Y484833D01*
X1116365Y486292D01*
X1116055Y487750D01*
X1115125Y489000D01*
X1114040Y489417D01*
X1109235D01*
G01X1125200Y482750D02*
X1123960Y482958D01*
X1122875Y483791D01*
X1121945Y485042D01*
X1121325Y486500D01*
X1121015Y488167D01*
Y489833D01*
X1121325Y491500D01*
X1121945Y492958D01*
X1122875Y494208D01*
X1123960Y495042D01*
X1125200Y495250D01*
X1126440Y495042D01*
X1127525Y494208D01*
X1128455Y492958D01*
X1129075Y491500D01*
X1129385Y489833D01*
Y488167D01*
X1129075Y486500D01*
X1128455Y485042D01*
X1127525Y483791D01*
X1126440Y482958D01*
X1125200Y482750D01*
G01X1137600Y495250D02*
Y482750D01*
G01X1134035Y495250D02*
X1141165D01*
G01X1150000D02*
Y482750D01*
G01X1146435Y495250D02*
X1153565D01*
G01X1162400Y482750D02*
X1161160Y482958D01*
X1160075Y483791D01*
X1159145Y485042D01*
X1158525Y486500D01*
X1158215Y488167D01*
Y489833D01*
X1158525Y491500D01*
X1159145Y492958D01*
X1160075Y494208D01*
X1161160Y495042D01*
X1162400Y495250D01*
X1163640Y495042D01*
X1164725Y494208D01*
X1165655Y492958D01*
X1166275Y491500D01*
X1166585Y489833D01*
Y488167D01*
X1166275Y486500D01*
X1165655Y485042D01*
X1164725Y483791D01*
X1163640Y482958D01*
X1162400Y482750D01*
G01X1170770D02*
Y495250D01*
X1174800Y484833D01*
X1178830Y495250D01*
Y482750D01*
G01X891925Y457750D02*
X895800Y470250D01*
X899675Y457750D01*
G01X898280Y462125D02*
X893320D01*
G01X905100Y470250D02*
Y457750D01*
X911300D01*
G01X917500Y470250D02*
Y457750D01*
X923700D01*
G01X941990Y470250D02*
Y461292D01*
X942610Y459416D01*
X943850Y458167D01*
X945400Y457750D01*
X946950Y458167D01*
X948190Y459416D01*
X948810Y461292D01*
Y470250D01*
G01X954235Y457750D02*
Y470250D01*
X961365Y457750D01*
Y470250D01*
G01X968340D02*
X972060D01*
G01X970200D02*
Y457750D01*
G01X968340D02*
X972060D01*
G01X982600Y470250D02*
Y457750D01*
G01X979035Y470250D02*
X986165D01*
G01X991745Y459416D02*
X992985Y458375D01*
X994380Y457750D01*
X995620D01*
X996860Y458375D01*
X997790Y459416D01*
X998255Y460875D01*
X997945Y462333D01*
X997170Y463583D01*
X995775Y464417D01*
X993915Y464833D01*
X992830Y465667D01*
X992365Y467125D01*
X992675Y468583D01*
X993450Y469625D01*
X994535Y470250D01*
X995620D01*
X996705Y469833D01*
X997635Y468792D01*
G01X1015925Y457750D02*
X1019800Y470250D01*
X1023675Y457750D01*
G01X1022280Y462125D02*
X1017320D01*
G01X1029100Y457750D02*
Y470250D01*
X1032975D01*
X1034215Y469625D01*
X1034990Y468792D01*
X1035300Y467125D01*
X1034990Y465458D01*
X1034060Y464417D01*
X1032975Y463792D01*
X1029100D01*
G01X1032975D02*
X1035300Y457750D01*
G01X1047700D02*
X1041500D01*
Y470250D01*
X1047700D01*
G01X1045220Y464208D02*
X1041500D01*
G01X1067540Y470250D02*
X1071260D01*
G01X1069400D02*
Y457750D01*
G01X1067540D02*
X1071260D01*
G01X1078235D02*
Y470250D01*
X1085365Y457750D01*
Y470250D01*
G01X1102570Y457750D02*
Y470250D01*
X1106600Y459833D01*
X1110630Y470250D01*
Y457750D01*
G01X1117140Y470250D02*
X1120860D01*
G01X1119000D02*
Y457750D01*
G01X1117140D02*
X1120860D01*
G01X1128300Y470250D02*
Y457750D01*
X1134500D01*
G01X1140545Y459416D02*
X1141785Y458375D01*
X1143180Y457750D01*
X1144420D01*
X1145660Y458375D01*
X1146590Y459416D01*
X1147055Y460875D01*
X1146745Y462333D01*
X1145970Y463583D01*
X1144575Y464417D01*
X1142715Y464833D01*
X1141630Y465667D01*
X1141165Y467125D01*
X1141475Y468583D01*
X1142250Y469625D01*
X1143335Y470250D01*
X1144420D01*
X1145505Y469833D01*
X1146435Y468792D01*
G01X937650Y90900D02*
Y103400D01*
X935790Y100900D01*
G01Y90900D02*
X939510D01*
G01X951910D02*
Y103400D01*
X946175Y94442D01*
X953925D01*
G01X962450Y103400D02*
X961210Y102983D01*
X960280Y101942D01*
X959660Y100692D01*
X959195Y99025D01*
X959040Y97150D01*
X959195Y95275D01*
X959660Y93608D01*
X960280Y92358D01*
X961210Y91317D01*
X962450Y90900D01*
X963690Y91317D01*
X964620Y92358D01*
X965240Y93608D01*
X965705Y95275D01*
X965860Y97150D01*
X965705Y99025D01*
X965240Y100692D01*
X964620Y101942D01*
X963690Y102983D01*
X962450Y103400D01*
G01X974850Y90483D02*
X974540Y90692D01*
Y91108D01*
X974850Y91317D01*
X975160Y91108D01*
Y90692D01*
X974850Y90483D01*
G01X987250Y103400D02*
X986010Y102983D01*
X985080Y101942D01*
X984460Y100692D01*
X983995Y99025D01*
X983840Y97150D01*
X983995Y95275D01*
X984460Y93608D01*
X985080Y92358D01*
X986010Y91317D01*
X987250Y90900D01*
X988490Y91317D01*
X989420Y92358D01*
X990040Y93608D01*
X990505Y95275D01*
X990660Y97150D01*
X990505Y99025D01*
X990040Y100692D01*
X989420Y101942D01*
X988490Y102983D01*
X987250Y103400D01*
G01X937650Y62800D02*
Y75300D01*
X935790Y72800D01*
G01Y62800D02*
X939510D01*
G01X951910D02*
Y75300D01*
X946175Y66342D01*
X953925D01*
G01X959505Y73217D02*
X960435Y74466D01*
X961520Y75092D01*
X962760Y75300D01*
X964310Y74883D01*
X965395Y73842D01*
X965705Y72592D01*
X965550Y71341D01*
X964930Y70300D01*
X961830Y68217D01*
X960435Y66758D01*
X959505Y64675D01*
X959195Y62800D01*
X965705D01*
G01X974850Y62383D02*
X974540Y62592D01*
Y63008D01*
X974850Y63217D01*
X975160Y63008D01*
Y62592D01*
X974850Y62383D01*
G01X987250Y75300D02*
X986010Y74883D01*
X985080Y73842D01*
X984460Y72592D01*
X983995Y70925D01*
X983840Y69050D01*
X983995Y67175D01*
X984460Y65508D01*
X985080Y64258D01*
X986010Y63217D01*
X987250Y62800D01*
X988490Y63217D01*
X989420Y64258D01*
X990040Y65508D01*
X990505Y67175D01*
X990660Y69050D01*
X990505Y70925D01*
X990040Y72592D01*
X989420Y73842D01*
X988490Y74883D01*
X987250Y75300D01*
G01X937650Y119000D02*
Y131500D01*
X935790Y129000D01*
G01Y119000D02*
X939510D01*
G01X947105Y129417D02*
X948035Y130666D01*
X949120Y131292D01*
X950360Y131500D01*
X951910Y131083D01*
X952995Y130042D01*
X953305Y128792D01*
X953150Y127541D01*
X952530Y126500D01*
X949430Y124417D01*
X948035Y122958D01*
X947105Y120875D01*
X946795Y119000D01*
X953305D01*
G01X959505Y124208D02*
X960590Y125667D01*
X961520Y126500D01*
X962760Y126917D01*
X963845Y126500D01*
X964620Y125667D01*
X965240Y124417D01*
X965395Y122958D01*
X965240Y121708D01*
X964620Y120458D01*
X963690Y119417D01*
X962605Y119000D01*
X961365Y119417D01*
X960280Y120666D01*
X959660Y122542D01*
X959505Y124625D01*
X959815Y127333D01*
X960280Y128792D01*
X961055Y130250D01*
X962140Y131292D01*
X963225Y131500D01*
X964310Y131083D01*
X965085Y130042D01*
G01X974850Y118583D02*
X974540Y118792D01*
Y119208D01*
X974850Y119417D01*
X975160Y119208D01*
Y118792D01*
X974850Y118583D01*
G01X987250Y131500D02*
X986010Y131083D01*
X985080Y130042D01*
X984460Y128792D01*
X983995Y127125D01*
X983840Y125250D01*
X983995Y123375D01*
X984460Y121708D01*
X985080Y120458D01*
X986010Y119417D01*
X987250Y119000D01*
X988490Y119417D01*
X989420Y120458D01*
X990040Y121708D01*
X990505Y123375D01*
X990660Y125250D01*
X990505Y127125D01*
X990040Y128792D01*
X989420Y130042D01*
X988490Y131083D01*
X987250Y131500D01*
G01X941215Y176658D02*
X942300Y175617D01*
X943540Y175200D01*
X944780Y175617D01*
X945865Y176866D01*
X946640Y178742D01*
X946950Y180617D01*
Y182908D01*
X946640Y184783D01*
X945865Y186450D01*
X944935Y187283D01*
X943850Y187700D01*
X942610Y187283D01*
X941680Y186450D01*
X941060Y185200D01*
X940750Y183533D01*
X941060Y182075D01*
X941835Y180617D01*
X942765Y179783D01*
X943850Y179575D01*
X945090Y179991D01*
X946020Y181033D01*
X946950Y182908D01*
G01X953615Y176658D02*
X954700Y175617D01*
X955940Y175200D01*
X957180Y175617D01*
X958265Y176866D01*
X959040Y178742D01*
X959350Y180617D01*
Y182908D01*
X959040Y184783D01*
X958265Y186450D01*
X957335Y187283D01*
X956250Y187700D01*
X955010Y187283D01*
X954080Y186450D01*
X953460Y185200D01*
X953150Y183533D01*
X953460Y182075D01*
X954235Y180617D01*
X955165Y179783D01*
X956250Y179575D01*
X957490Y179991D01*
X958420Y181033D01*
X959350Y182908D01*
G01X968650Y174783D02*
X968340Y174992D01*
Y175408D01*
X968650Y175617D01*
X968960Y175408D01*
Y174992D01*
X968650Y174783D01*
G01X981050Y187700D02*
X979810Y187283D01*
X978880Y186242D01*
X978260Y184992D01*
X977795Y183325D01*
X977640Y181450D01*
X977795Y179575D01*
X978260Y177908D01*
X978880Y176658D01*
X979810Y175617D01*
X981050Y175200D01*
X982290Y175617D01*
X983220Y176658D01*
X983840Y177908D01*
X984305Y179575D01*
X984460Y181450D01*
X984305Y183325D01*
X983840Y184992D01*
X983220Y186242D01*
X982290Y187283D01*
X981050Y187700D01*
G01X937650Y147100D02*
Y159600D01*
X935790Y157100D01*
G01Y147100D02*
X939510D01*
G01X950050D02*
Y159600D01*
X948190Y157100D01*
G01Y147100D02*
X951910D01*
G01X959040Y148975D02*
X959970Y147933D01*
X961055Y147308D01*
X962450Y147100D01*
X963845Y147517D01*
X964930Y148350D01*
X965705Y149808D01*
X965860Y151475D01*
X965550Y153142D01*
X964775Y154183D01*
X963690Y155017D01*
X962605Y155225D01*
X961520Y155017D01*
X960125Y154183D01*
X960590Y159600D01*
X964775D01*
G01X974850Y146683D02*
X974540Y146892D01*
Y147308D01*
X974850Y147517D01*
X975160Y147308D01*
Y146892D01*
X974850Y146683D01*
G01X987250Y159600D02*
X986010Y159183D01*
X985080Y158142D01*
X984460Y156892D01*
X983995Y155225D01*
X983840Y153350D01*
X983995Y151475D01*
X984460Y149808D01*
X985080Y148558D01*
X986010Y147517D01*
X987250Y147100D01*
X988490Y147517D01*
X989420Y148558D01*
X990040Y149808D01*
X990505Y151475D01*
X990660Y153350D01*
X990505Y155225D01*
X990040Y156892D01*
X989420Y158142D01*
X988490Y159183D01*
X987250Y159600D01*
G01X937650Y231400D02*
Y243900D01*
X935790Y241400D01*
G01Y231400D02*
X939510D01*
G01X946640Y233275D02*
X947570Y232233D01*
X948655Y231608D01*
X950050Y231400D01*
X951445Y231817D01*
X952530Y232650D01*
X953305Y234108D01*
X953460Y235775D01*
X953150Y237442D01*
X952375Y238483D01*
X951290Y239317D01*
X950205Y239525D01*
X949120Y239317D01*
X947725Y238483D01*
X948190Y243900D01*
X952375D01*
G01X962450Y231400D02*
X963535Y231608D01*
X964775Y232233D01*
X965550Y233275D01*
X965860Y234733D01*
X965550Y236191D01*
X964620Y237442D01*
X963225Y238067D01*
X961675D01*
X960745Y238483D01*
X959970Y239525D01*
X959660Y240983D01*
X960125Y242442D01*
X961210Y243483D01*
X962450Y243900D01*
X963690Y243483D01*
X964775Y242442D01*
X965240Y240983D01*
X964930Y239525D01*
X964155Y238483D01*
X963225Y238067D01*
X961675D01*
X960280Y237442D01*
X959350Y236191D01*
X959040Y234733D01*
X959350Y233275D01*
X960125Y232233D01*
X961365Y231608D01*
X962450Y231400D01*
G01X974850Y230983D02*
X974540Y231192D01*
Y231608D01*
X974850Y231817D01*
X975160Y231608D01*
Y231192D01*
X974850Y230983D01*
G01X987250Y243900D02*
X986010Y243483D01*
X985080Y242442D01*
X984460Y241192D01*
X983995Y239525D01*
X983840Y237650D01*
X983995Y235775D01*
X984460Y234108D01*
X985080Y232858D01*
X986010Y231817D01*
X987250Y231400D01*
X988490Y231817D01*
X989420Y232858D01*
X990040Y234108D01*
X990505Y235775D01*
X990660Y237650D01*
X990505Y239525D01*
X990040Y241192D01*
X989420Y242442D01*
X988490Y243483D01*
X987250Y243900D01*
G01X937650Y203300D02*
Y215800D01*
X935790Y213300D01*
G01Y203300D02*
X939510D01*
G01X947415Y204758D02*
X948500Y203717D01*
X949740Y203300D01*
X950980Y203717D01*
X952065Y204966D01*
X952840Y206842D01*
X953150Y208717D01*
Y211008D01*
X952840Y212883D01*
X952065Y214550D01*
X951135Y215383D01*
X950050Y215800D01*
X948810Y215383D01*
X947880Y214550D01*
X947260Y213300D01*
X946950Y211633D01*
X947260Y210175D01*
X948035Y208717D01*
X948965Y207883D01*
X950050Y207675D01*
X951290Y208091D01*
X952220Y209133D01*
X953150Y211008D01*
G01X959815Y204758D02*
X960900Y203717D01*
X962140Y203300D01*
X963380Y203717D01*
X964465Y204966D01*
X965240Y206842D01*
X965550Y208717D01*
Y211008D01*
X965240Y212883D01*
X964465Y214550D01*
X963535Y215383D01*
X962450Y215800D01*
X961210Y215383D01*
X960280Y214550D01*
X959660Y213300D01*
X959350Y211633D01*
X959660Y210175D01*
X960435Y208717D01*
X961365Y207883D01*
X962450Y207675D01*
X963690Y208091D01*
X964620Y209133D01*
X965550Y211008D01*
G01X974850Y202883D02*
X974540Y203092D01*
Y203508D01*
X974850Y203717D01*
X975160Y203508D01*
Y203092D01*
X974850Y202883D01*
G01X987250Y215800D02*
X986010Y215383D01*
X985080Y214342D01*
X984460Y213092D01*
X983995Y211425D01*
X983840Y209550D01*
X983995Y207675D01*
X984460Y206008D01*
X985080Y204758D01*
X986010Y203717D01*
X987250Y203300D01*
X988490Y203717D01*
X989420Y204758D01*
X990040Y206008D01*
X990505Y207675D01*
X990660Y209550D01*
X990505Y211425D01*
X990040Y213092D01*
X989420Y214342D01*
X988490Y215383D01*
X987250Y215800D01*
G01X945710Y287600D02*
Y300100D01*
X939975Y291142D01*
X947725D01*
G01X956250Y287600D02*
Y300100D01*
X954390Y297600D01*
G01Y287600D02*
X958110D01*
G01X968650Y287183D02*
X968340Y287392D01*
Y287808D01*
X968650Y288017D01*
X968960Y287808D01*
Y287392D01*
X968650Y287183D01*
G01X981050Y300100D02*
X979810Y299683D01*
X978880Y298642D01*
X978260Y297392D01*
X977795Y295725D01*
X977640Y293850D01*
X977795Y291975D01*
X978260Y290308D01*
X978880Y289058D01*
X979810Y288017D01*
X981050Y287600D01*
X982290Y288017D01*
X983220Y289058D01*
X983840Y290308D01*
X984305Y291975D01*
X984460Y293850D01*
X984305Y295725D01*
X983840Y297392D01*
X983220Y298642D01*
X982290Y299683D01*
X981050Y300100D01*
G01X937650Y259500D02*
Y272000D01*
X935790Y269500D01*
G01Y259500D02*
X939510D01*
G01X946640Y262000D02*
X947570Y260541D01*
X948810Y259708D01*
X950205Y259500D01*
X951445Y259708D01*
X952685Y260750D01*
X953460Y262000D01*
X953615Y263250D01*
X953305Y264708D01*
X952220Y265750D01*
X951135Y266167D01*
X949740D01*
G01X951135D02*
X952065Y266792D01*
X952840Y267833D01*
X953150Y269083D01*
X952840Y270333D01*
X952065Y271375D01*
X950670Y272000D01*
X949275Y271792D01*
X947880Y270958D01*
G01X962450Y259500D02*
X963535Y259708D01*
X964775Y260333D01*
X965550Y261375D01*
X965860Y262833D01*
X965550Y264291D01*
X964620Y265542D01*
X963225Y266167D01*
X961675D01*
X960745Y266583D01*
X959970Y267625D01*
X959660Y269083D01*
X960125Y270542D01*
X961210Y271583D01*
X962450Y272000D01*
X963690Y271583D01*
X964775Y270542D01*
X965240Y269083D01*
X964930Y267625D01*
X964155Y266583D01*
X963225Y266167D01*
X961675D01*
X960280Y265542D01*
X959350Y264291D01*
X959040Y262833D01*
X959350Y261375D01*
X960125Y260333D01*
X961365Y259708D01*
X962450Y259500D01*
G01X974850Y259083D02*
X974540Y259292D01*
Y259708D01*
X974850Y259917D01*
X975160Y259708D01*
Y259292D01*
X974850Y259083D01*
G01X987250Y272000D02*
X986010Y271583D01*
X985080Y270542D01*
X984460Y269292D01*
X983995Y267625D01*
X983840Y265750D01*
X983995Y263875D01*
X984460Y262208D01*
X985080Y260958D01*
X986010Y259917D01*
X987250Y259500D01*
X988490Y259917D01*
X989420Y260958D01*
X990040Y262208D01*
X990505Y263875D01*
X990660Y265750D01*
X990505Y267625D01*
X990040Y269292D01*
X989420Y270542D01*
X988490Y271583D01*
X987250Y272000D01*
G01X940440Y346300D02*
X941370Y344841D01*
X942610Y344008D01*
X944005Y343800D01*
X945245Y344008D01*
X946485Y345050D01*
X947260Y346300D01*
X947415Y347550D01*
X947105Y349008D01*
X946020Y350050D01*
X944935Y350467D01*
X943540D01*
G01X944935D02*
X945865Y351092D01*
X946640Y352133D01*
X946950Y353383D01*
X946640Y354633D01*
X945865Y355675D01*
X944470Y356300D01*
X943075Y356092D01*
X941680Y355258D01*
G01X952840Y345675D02*
X953770Y344633D01*
X954855Y344008D01*
X956250Y343800D01*
X957645Y344217D01*
X958730Y345050D01*
X959505Y346508D01*
X959660Y348175D01*
X959350Y349842D01*
X958575Y350883D01*
X957490Y351717D01*
X956405Y351925D01*
X955320Y351717D01*
X953925Y350883D01*
X954390Y356300D01*
X958575D01*
G01X968650Y343383D02*
X968340Y343592D01*
Y344008D01*
X968650Y344217D01*
X968960Y344008D01*
Y343592D01*
X968650Y343383D01*
G01X981050Y356300D02*
X979810Y355883D01*
X978880Y354842D01*
X978260Y353592D01*
X977795Y351925D01*
X977640Y350050D01*
X977795Y348175D01*
X978260Y346508D01*
X978880Y345258D01*
X979810Y344217D01*
X981050Y343800D01*
X982290Y344217D01*
X983220Y345258D01*
X983840Y346508D01*
X984305Y348175D01*
X984460Y350050D01*
X984305Y351925D01*
X983840Y353592D01*
X983220Y354842D01*
X982290Y355883D01*
X981050Y356300D01*
G01X945710Y315700D02*
Y328200D01*
X939975Y319242D01*
X947725D01*
G01X956250Y328200D02*
X955010Y327783D01*
X954080Y326742D01*
X953460Y325492D01*
X952995Y323825D01*
X952840Y321950D01*
X952995Y320075D01*
X953460Y318408D01*
X954080Y317158D01*
X955010Y316117D01*
X956250Y315700D01*
X957490Y316117D01*
X958420Y317158D01*
X959040Y318408D01*
X959505Y320075D01*
X959660Y321950D01*
X959505Y323825D01*
X959040Y325492D01*
X958420Y326742D01*
X957490Y327783D01*
X956250Y328200D01*
G01X968650Y315283D02*
X968340Y315492D01*
Y315908D01*
X968650Y316117D01*
X968960Y315908D01*
Y315492D01*
X968650Y315283D01*
G01X981050Y328200D02*
X979810Y327783D01*
X978880Y326742D01*
X978260Y325492D01*
X977795Y323825D01*
X977640Y321950D01*
X977795Y320075D01*
X978260Y318408D01*
X978880Y317158D01*
X979810Y316117D01*
X981050Y315700D01*
X982290Y316117D01*
X983220Y317158D01*
X983840Y318408D01*
X984305Y320075D01*
X984460Y321950D01*
X984305Y323825D01*
X983840Y325492D01*
X983220Y326742D01*
X982290Y327783D01*
X981050Y328200D01*
G01X943850Y400000D02*
Y412500D01*
X941990Y410000D01*
G01Y400000D02*
X945710D01*
G01X953305Y410417D02*
X954235Y411666D01*
X955320Y412292D01*
X956560Y412500D01*
X958110Y412083D01*
X959195Y411042D01*
X959505Y409792D01*
X959350Y408541D01*
X958730Y407500D01*
X955630Y405417D01*
X954235Y403958D01*
X953305Y401875D01*
X952995Y400000D01*
X959505D01*
G01X968650Y399583D02*
X968340Y399792D01*
Y400208D01*
X968650Y400417D01*
X968960Y400208D01*
Y399792D01*
X968650Y399583D01*
G01X981050Y412500D02*
X979810Y412083D01*
X978880Y411042D01*
X978260Y409792D01*
X977795Y408125D01*
X977640Y406250D01*
X977795Y404375D01*
X978260Y402708D01*
X978880Y401458D01*
X979810Y400417D01*
X981050Y400000D01*
X982290Y400417D01*
X983220Y401458D01*
X983840Y402708D01*
X984305Y404375D01*
X984460Y406250D01*
X984305Y408125D01*
X983840Y409792D01*
X983220Y411042D01*
X982290Y412083D01*
X981050Y412500D01*
G01X943850Y371900D02*
Y384400D01*
X941990Y381900D01*
G01Y371900D02*
X945710D01*
G01X953305Y377108D02*
X954390Y378567D01*
X955320Y379400D01*
X956560Y379817D01*
X957645Y379400D01*
X958420Y378567D01*
X959040Y377317D01*
X959195Y375858D01*
X959040Y374608D01*
X958420Y373358D01*
X957490Y372317D01*
X956405Y371900D01*
X955165Y372317D01*
X954080Y373566D01*
X953460Y375442D01*
X953305Y377525D01*
X953615Y380233D01*
X954080Y381692D01*
X954855Y383150D01*
X955940Y384192D01*
X957025Y384400D01*
X958110Y383983D01*
X958885Y382942D01*
G01X968650Y371483D02*
X968340Y371692D01*
Y372108D01*
X968650Y372317D01*
X968960Y372108D01*
Y371692D01*
X968650Y371483D01*
G01X981050Y384400D02*
X979810Y383983D01*
X978880Y382942D01*
X978260Y381692D01*
X977795Y380025D01*
X977640Y378150D01*
X977795Y376275D01*
X978260Y374608D01*
X978880Y373358D01*
X979810Y372317D01*
X981050Y371900D01*
X982290Y372317D01*
X983220Y373358D01*
X983840Y374608D01*
X984305Y376275D01*
X984460Y378150D01*
X984305Y380025D01*
X983840Y381692D01*
X983220Y382942D01*
X982290Y383983D01*
X981050Y384400D01*
G01X940595Y431316D02*
X941835Y430275D01*
X943230Y429650D01*
X944470D01*
X945710Y430275D01*
X946640Y431316D01*
X947105Y432775D01*
X946795Y434233D01*
X946020Y435483D01*
X944625Y436317D01*
X942765Y436733D01*
X941680Y437567D01*
X941215Y439025D01*
X941525Y440483D01*
X942300Y441525D01*
X943385Y442150D01*
X944470D01*
X945555Y441733D01*
X946485Y440692D01*
G01X954390Y442150D02*
X958110D01*
G01X956250D02*
Y429650D01*
G01X954390D02*
X958110D01*
G01X965705Y442150D02*
X971595D01*
X965705Y429650D01*
X971595D01*
G01X984150D02*
X977950D01*
Y442150D01*
X984150D01*
G01X981670Y436108D02*
X977950D01*
G01X1057000Y448400D02*
Y55000D01*
G01X1061185Y90900D02*
Y103400D01*
X1068315Y90900D01*
Y103400D01*
G01X1077150Y90900D02*
X1075910Y91108D01*
X1074825Y91941D01*
X1073895Y93192D01*
X1073275Y94650D01*
X1072965Y96317D01*
Y97983D01*
X1073275Y99650D01*
X1073895Y101108D01*
X1074825Y102358D01*
X1075910Y103192D01*
X1077150Y103400D01*
X1078390Y103192D01*
X1079475Y102358D01*
X1080405Y101108D01*
X1081025Y99650D01*
X1081335Y97983D01*
Y96317D01*
X1081025Y94650D01*
X1080405Y93192D01*
X1079475Y91941D01*
X1078390Y91108D01*
X1077150Y90900D01*
G01X1085985D02*
Y103400D01*
X1093115Y90900D01*
Y103400D01*
G01X1099935Y95067D02*
X1103965D01*
G01X1111250Y90900D02*
Y103400D01*
X1114970D01*
X1116210Y102775D01*
X1117140Y101317D01*
X1117450Y99650D01*
X1117140Y97983D01*
X1116365Y96733D01*
X1114970Y96108D01*
X1111250D01*
G01X1123650Y103400D02*
Y90900D01*
X1129850D01*
G01X1135275D02*
X1139150Y103400D01*
X1143025Y90900D01*
G01X1141630Y95275D02*
X1136670D01*
G01X1151550Y103400D02*
Y90900D01*
G01X1147985Y103400D02*
X1155115D01*
G01X1167050Y90900D02*
X1160850D01*
Y103400D01*
X1167050D01*
G01X1164570Y97358D02*
X1160850D01*
G01X1172940Y90900D02*
Y103400D01*
X1176040D01*
X1177280Y102775D01*
X1178210Y101942D01*
X1178985Y100692D01*
X1179605Y99233D01*
X1179760Y97150D01*
X1179605Y95067D01*
X1178985Y93608D01*
X1178210Y92358D01*
X1177280Y91525D01*
X1176040Y90900D01*
X1172940D01*
G01X1061185Y62800D02*
Y75300D01*
X1068315Y62800D01*
Y75300D01*
G01X1077150Y62800D02*
X1075910Y63008D01*
X1074825Y63841D01*
X1073895Y65092D01*
X1073275Y66550D01*
X1072965Y68217D01*
Y69883D01*
X1073275Y71550D01*
X1073895Y73008D01*
X1074825Y74258D01*
X1075910Y75092D01*
X1077150Y75300D01*
X1078390Y75092D01*
X1079475Y74258D01*
X1080405Y73008D01*
X1081025Y71550D01*
X1081335Y69883D01*
Y68217D01*
X1081025Y66550D01*
X1080405Y65092D01*
X1079475Y63841D01*
X1078390Y63008D01*
X1077150Y62800D01*
G01X1085985D02*
Y75300D01*
X1093115Y62800D01*
Y75300D01*
G01X1099935Y66967D02*
X1103965D01*
G01X1111250Y62800D02*
Y75300D01*
X1114970D01*
X1116210Y74675D01*
X1117140Y73217D01*
X1117450Y71550D01*
X1117140Y69883D01*
X1116365Y68633D01*
X1114970Y68008D01*
X1111250D01*
G01X1123650Y75300D02*
Y62800D01*
X1129850D01*
G01X1135275D02*
X1139150Y75300D01*
X1143025Y62800D01*
G01X1141630Y67175D02*
X1136670D01*
G01X1151550Y75300D02*
Y62800D01*
G01X1147985Y75300D02*
X1155115D01*
G01X1167050Y62800D02*
X1160850D01*
Y75300D01*
X1167050D01*
G01X1164570Y69258D02*
X1160850D01*
G01X1172940Y62800D02*
Y75300D01*
X1176040D01*
X1177280Y74675D01*
X1178210Y73842D01*
X1178985Y72592D01*
X1179605Y71133D01*
X1179760Y69050D01*
X1179605Y66967D01*
X1178985Y65508D01*
X1178210Y64258D01*
X1177280Y63425D01*
X1176040Y62800D01*
X1172940D01*
G01X1061185Y119000D02*
Y131500D01*
X1068315Y119000D01*
Y131500D01*
G01X1077150Y119000D02*
X1075910Y119208D01*
X1074825Y120041D01*
X1073895Y121292D01*
X1073275Y122750D01*
X1072965Y124417D01*
Y126083D01*
X1073275Y127750D01*
X1073895Y129208D01*
X1074825Y130458D01*
X1075910Y131292D01*
X1077150Y131500D01*
X1078390Y131292D01*
X1079475Y130458D01*
X1080405Y129208D01*
X1081025Y127750D01*
X1081335Y126083D01*
Y124417D01*
X1081025Y122750D01*
X1080405Y121292D01*
X1079475Y120041D01*
X1078390Y119208D01*
X1077150Y119000D01*
G01X1085985D02*
Y131500D01*
X1093115Y119000D01*
Y131500D01*
G01X1099935Y123167D02*
X1103965D01*
G01X1111250Y119000D02*
Y131500D01*
X1114970D01*
X1116210Y130875D01*
X1117140Y129417D01*
X1117450Y127750D01*
X1117140Y126083D01*
X1116365Y124833D01*
X1114970Y124208D01*
X1111250D01*
G01X1123650Y131500D02*
Y119000D01*
X1129850D01*
G01X1135275D02*
X1139150Y131500D01*
X1143025Y119000D01*
G01X1141630Y123375D02*
X1136670D01*
G01X1151550Y131500D02*
Y119000D01*
G01X1147985Y131500D02*
X1155115D01*
G01X1167050Y119000D02*
X1160850D01*
Y131500D01*
X1167050D01*
G01X1164570Y125458D02*
X1160850D01*
G01X1172940Y119000D02*
Y131500D01*
X1176040D01*
X1177280Y130875D01*
X1178210Y130042D01*
X1178985Y128792D01*
X1179605Y127333D01*
X1179760Y125250D01*
X1179605Y123167D01*
X1178985Y121708D01*
X1178210Y120458D01*
X1177280Y119625D01*
X1176040Y119000D01*
X1172940D01*
G01X1061185Y175200D02*
Y187700D01*
X1068315Y175200D01*
Y187700D01*
G01X1077150Y175200D02*
X1075910Y175408D01*
X1074825Y176241D01*
X1073895Y177492D01*
X1073275Y178950D01*
X1072965Y180617D01*
Y182283D01*
X1073275Y183950D01*
X1073895Y185408D01*
X1074825Y186658D01*
X1075910Y187492D01*
X1077150Y187700D01*
X1078390Y187492D01*
X1079475Y186658D01*
X1080405Y185408D01*
X1081025Y183950D01*
X1081335Y182283D01*
Y180617D01*
X1081025Y178950D01*
X1080405Y177492D01*
X1079475Y176241D01*
X1078390Y175408D01*
X1077150Y175200D01*
G01X1085985D02*
Y187700D01*
X1093115Y175200D01*
Y187700D01*
G01X1099935Y179367D02*
X1103965D01*
G01X1111250Y175200D02*
Y187700D01*
X1114970D01*
X1116210Y187075D01*
X1117140Y185617D01*
X1117450Y183950D01*
X1117140Y182283D01*
X1116365Y181033D01*
X1114970Y180408D01*
X1111250D01*
G01X1123650Y187700D02*
Y175200D01*
X1129850D01*
G01X1135275D02*
X1139150Y187700D01*
X1143025Y175200D01*
G01X1141630Y179575D02*
X1136670D01*
G01X1151550Y187700D02*
Y175200D01*
G01X1147985Y187700D02*
X1155115D01*
G01X1167050Y175200D02*
X1160850D01*
Y187700D01*
X1167050D01*
G01X1164570Y181658D02*
X1160850D01*
G01X1172940Y175200D02*
Y187700D01*
X1176040D01*
X1177280Y187075D01*
X1178210Y186242D01*
X1178985Y184992D01*
X1179605Y183533D01*
X1179760Y181450D01*
X1179605Y179367D01*
X1178985Y177908D01*
X1178210Y176658D01*
X1177280Y175825D01*
X1176040Y175200D01*
X1172940D01*
G01X1061185Y147100D02*
Y159600D01*
X1068315Y147100D01*
Y159600D01*
G01X1077150Y147100D02*
X1075910Y147308D01*
X1074825Y148141D01*
X1073895Y149392D01*
X1073275Y150850D01*
X1072965Y152517D01*
Y154183D01*
X1073275Y155850D01*
X1073895Y157308D01*
X1074825Y158558D01*
X1075910Y159392D01*
X1077150Y159600D01*
X1078390Y159392D01*
X1079475Y158558D01*
X1080405Y157308D01*
X1081025Y155850D01*
X1081335Y154183D01*
Y152517D01*
X1081025Y150850D01*
X1080405Y149392D01*
X1079475Y148141D01*
X1078390Y147308D01*
X1077150Y147100D01*
G01X1085985D02*
Y159600D01*
X1093115Y147100D01*
Y159600D01*
G01X1099935Y151267D02*
X1103965D01*
G01X1111250Y147100D02*
Y159600D01*
X1114970D01*
X1116210Y158975D01*
X1117140Y157517D01*
X1117450Y155850D01*
X1117140Y154183D01*
X1116365Y152933D01*
X1114970Y152308D01*
X1111250D01*
G01X1123650Y159600D02*
Y147100D01*
X1129850D01*
G01X1135275D02*
X1139150Y159600D01*
X1143025Y147100D01*
G01X1141630Y151475D02*
X1136670D01*
G01X1151550Y159600D02*
Y147100D01*
G01X1147985Y159600D02*
X1155115D01*
G01X1167050Y147100D02*
X1160850D01*
Y159600D01*
X1167050D01*
G01X1164570Y153558D02*
X1160850D01*
G01X1172940Y147100D02*
Y159600D01*
X1176040D01*
X1177280Y158975D01*
X1178210Y158142D01*
X1178985Y156892D01*
X1179605Y155433D01*
X1179760Y153350D01*
X1179605Y151267D01*
X1178985Y149808D01*
X1178210Y148558D01*
X1177280Y147725D01*
X1176040Y147100D01*
X1172940D01*
G01X1086450Y231400D02*
Y243900D01*
X1090170D01*
X1091410Y243275D01*
X1092340Y241817D01*
X1092650Y240150D01*
X1092340Y238483D01*
X1091565Y237233D01*
X1090170Y236608D01*
X1086450D01*
G01X1098850Y243900D02*
Y231400D01*
X1105050D01*
G01X1110475D02*
X1114350Y243900D01*
X1118225Y231400D01*
G01X1116830Y235775D02*
X1111870D01*
G01X1126750Y243900D02*
Y231400D01*
G01X1123185Y243900D02*
X1130315D01*
G01X1142250Y231400D02*
X1136050D01*
Y243900D01*
X1142250D01*
G01X1139770Y237858D02*
X1136050D01*
G01X1148140Y231400D02*
Y243900D01*
X1151240D01*
X1152480Y243275D01*
X1153410Y242442D01*
X1154185Y241192D01*
X1154805Y239733D01*
X1154960Y237650D01*
X1154805Y235567D01*
X1154185Y234108D01*
X1153410Y232858D01*
X1152480Y232025D01*
X1151240Y231400D01*
X1148140D01*
G01X1086450Y203300D02*
Y215800D01*
X1090170D01*
X1091410Y215175D01*
X1092340Y213717D01*
X1092650Y212050D01*
X1092340Y210383D01*
X1091565Y209133D01*
X1090170Y208508D01*
X1086450D01*
G01X1098850Y215800D02*
Y203300D01*
X1105050D01*
G01X1110475D02*
X1114350Y215800D01*
X1118225Y203300D01*
G01X1116830Y207675D02*
X1111870D01*
G01X1126750Y215800D02*
Y203300D01*
G01X1123185Y215800D02*
X1130315D01*
G01X1142250Y203300D02*
X1136050D01*
Y215800D01*
X1142250D01*
G01X1139770Y209758D02*
X1136050D01*
G01X1148140Y203300D02*
Y215800D01*
X1151240D01*
X1152480Y215175D01*
X1153410Y214342D01*
X1154185Y213092D01*
X1154805Y211633D01*
X1154960Y209550D01*
X1154805Y207467D01*
X1154185Y206008D01*
X1153410Y204758D01*
X1152480Y203925D01*
X1151240Y203300D01*
X1148140D01*
G01X1086450Y287600D02*
Y300100D01*
X1090170D01*
X1091410Y299475D01*
X1092340Y298017D01*
X1092650Y296350D01*
X1092340Y294683D01*
X1091565Y293433D01*
X1090170Y292808D01*
X1086450D01*
G01X1098850Y300100D02*
Y287600D01*
X1105050D01*
G01X1110475D02*
X1114350Y300100D01*
X1118225Y287600D01*
G01X1116830Y291975D02*
X1111870D01*
G01X1126750Y300100D02*
Y287600D01*
G01X1123185Y300100D02*
X1130315D01*
G01X1142250Y287600D02*
X1136050D01*
Y300100D01*
X1142250D01*
G01X1139770Y294058D02*
X1136050D01*
G01X1148140Y287600D02*
Y300100D01*
X1151240D01*
X1152480Y299475D01*
X1153410Y298642D01*
X1154185Y297392D01*
X1154805Y295933D01*
X1154960Y293850D01*
X1154805Y291767D01*
X1154185Y290308D01*
X1153410Y289058D01*
X1152480Y288225D01*
X1151240Y287600D01*
X1148140D01*
G01X1086450Y259500D02*
Y272000D01*
X1090170D01*
X1091410Y271375D01*
X1092340Y269917D01*
X1092650Y268250D01*
X1092340Y266583D01*
X1091565Y265333D01*
X1090170Y264708D01*
X1086450D01*
G01X1098850Y272000D02*
Y259500D01*
X1105050D01*
G01X1110475D02*
X1114350Y272000D01*
X1118225Y259500D01*
G01X1116830Y263875D02*
X1111870D01*
G01X1126750Y272000D02*
Y259500D01*
G01X1123185Y272000D02*
X1130315D01*
G01X1142250Y259500D02*
X1136050D01*
Y272000D01*
X1142250D01*
G01X1139770Y265958D02*
X1136050D01*
G01X1148140Y259500D02*
Y272000D01*
X1151240D01*
X1152480Y271375D01*
X1153410Y270542D01*
X1154185Y269292D01*
X1154805Y267833D01*
X1154960Y265750D01*
X1154805Y263667D01*
X1154185Y262208D01*
X1153410Y260958D01*
X1152480Y260125D01*
X1151240Y259500D01*
X1148140D01*
G01X1086450Y343800D02*
Y356300D01*
X1090170D01*
X1091410Y355675D01*
X1092340Y354217D01*
X1092650Y352550D01*
X1092340Y350883D01*
X1091565Y349633D01*
X1090170Y349008D01*
X1086450D01*
G01X1098850Y356300D02*
Y343800D01*
X1105050D01*
G01X1110475D02*
X1114350Y356300D01*
X1118225Y343800D01*
G01X1116830Y348175D02*
X1111870D01*
G01X1126750Y356300D02*
Y343800D01*
G01X1123185Y356300D02*
X1130315D01*
G01X1142250Y343800D02*
X1136050D01*
Y356300D01*
X1142250D01*
G01X1139770Y350258D02*
X1136050D01*
G01X1148140Y343800D02*
Y356300D01*
X1151240D01*
X1152480Y355675D01*
X1153410Y354842D01*
X1154185Y353592D01*
X1154805Y352133D01*
X1154960Y350050D01*
X1154805Y347967D01*
X1154185Y346508D01*
X1153410Y345258D01*
X1152480Y344425D01*
X1151240Y343800D01*
X1148140D01*
G01X1086450Y315700D02*
Y328200D01*
X1090170D01*
X1091410Y327575D01*
X1092340Y326117D01*
X1092650Y324450D01*
X1092340Y322783D01*
X1091565Y321533D01*
X1090170Y320908D01*
X1086450D01*
G01X1098850Y328200D02*
Y315700D01*
X1105050D01*
G01X1110475D02*
X1114350Y328200D01*
X1118225Y315700D01*
G01X1116830Y320075D02*
X1111870D01*
G01X1126750Y328200D02*
Y315700D01*
G01X1123185Y328200D02*
X1130315D01*
G01X1142250Y315700D02*
X1136050D01*
Y328200D01*
X1142250D01*
G01X1139770Y322158D02*
X1136050D01*
G01X1148140Y315700D02*
Y328200D01*
X1151240D01*
X1152480Y327575D01*
X1153410Y326742D01*
X1154185Y325492D01*
X1154805Y324033D01*
X1154960Y321950D01*
X1154805Y319867D01*
X1154185Y318408D01*
X1153410Y317158D01*
X1152480Y316325D01*
X1151240Y315700D01*
X1148140D01*
G01X1086450Y400000D02*
Y412500D01*
X1090170D01*
X1091410Y411875D01*
X1092340Y410417D01*
X1092650Y408750D01*
X1092340Y407083D01*
X1091565Y405833D01*
X1090170Y405208D01*
X1086450D01*
G01X1098850Y412500D02*
Y400000D01*
X1105050D01*
G01X1110475D02*
X1114350Y412500D01*
X1118225Y400000D01*
G01X1116830Y404375D02*
X1111870D01*
G01X1126750Y412500D02*
Y400000D01*
G01X1123185Y412500D02*
X1130315D01*
G01X1142250Y400000D02*
X1136050D01*
Y412500D01*
X1142250D01*
G01X1139770Y406458D02*
X1136050D01*
G01X1148140Y400000D02*
Y412500D01*
X1151240D01*
X1152480Y411875D01*
X1153410Y411042D01*
X1154185Y409792D01*
X1154805Y408333D01*
X1154960Y406250D01*
X1154805Y404167D01*
X1154185Y402708D01*
X1153410Y401458D01*
X1152480Y400625D01*
X1151240Y400000D01*
X1148140D01*
G01X1086450Y371900D02*
Y384400D01*
X1090170D01*
X1091410Y383775D01*
X1092340Y382317D01*
X1092650Y380650D01*
X1092340Y378983D01*
X1091565Y377733D01*
X1090170Y377108D01*
X1086450D01*
G01X1098850Y384400D02*
Y371900D01*
X1105050D01*
G01X1110475D02*
X1114350Y384400D01*
X1118225Y371900D01*
G01X1116830Y376275D02*
X1111870D01*
G01X1126750Y384400D02*
Y371900D01*
G01X1123185Y384400D02*
X1130315D01*
G01X1142250Y371900D02*
X1136050D01*
Y384400D01*
X1142250D01*
G01X1139770Y378358D02*
X1136050D01*
G01X1148140Y371900D02*
Y384400D01*
X1151240D01*
X1152480Y383775D01*
X1153410Y382942D01*
X1154185Y381692D01*
X1154805Y380233D01*
X1154960Y378150D01*
X1154805Y376067D01*
X1154185Y374608D01*
X1153410Y373358D01*
X1152480Y372525D01*
X1151240Y371900D01*
X1148140D01*
G01X1086450Y429650D02*
Y442150D01*
X1090170D01*
X1091410Y441525D01*
X1092340Y440067D01*
X1092650Y438400D01*
X1092340Y436733D01*
X1091565Y435483D01*
X1090170Y434858D01*
X1086450D01*
G01X1098850Y442150D02*
Y429650D01*
X1105050D01*
G01X1110475D02*
X1114350Y442150D01*
X1118225Y429650D01*
G01X1116830Y434025D02*
X1111870D01*
G01X1126750Y442150D02*
Y429650D01*
G01X1123185Y442150D02*
X1130315D01*
G01X1142250Y429650D02*
X1136050D01*
Y442150D01*
X1142250D01*
G01X1139770Y436108D02*
X1136050D01*
G01X1148140Y429650D02*
Y442150D01*
X1151240D01*
X1152480Y441525D01*
X1153410Y440692D01*
X1154185Y439442D01*
X1154805Y437983D01*
X1154960Y435900D01*
X1154805Y433817D01*
X1154185Y432358D01*
X1153410Y431108D01*
X1152480Y430275D01*
X1151240Y429650D01*
X1148140D01*
G01X1184100Y448400D02*
Y55000D01*
G01X1210450Y287600D02*
Y300100D01*
X1208590Y297600D01*
G01Y287600D02*
X1212310D01*
G01X1222850Y300100D02*
X1221610Y299683D01*
X1220680Y298642D01*
X1220060Y297392D01*
X1219595Y295725D01*
X1219440Y293850D01*
X1219595Y291975D01*
X1220060Y290308D01*
X1220680Y289058D01*
X1221610Y288017D01*
X1222850Y287600D01*
X1224090Y288017D01*
X1225020Y289058D01*
X1225640Y290308D01*
X1226105Y291975D01*
X1226260Y293850D01*
X1226105Y295725D01*
X1225640Y297392D01*
X1225020Y298642D01*
X1224090Y299683D01*
X1222850Y300100D01*
G01X1237110Y287600D02*
Y300100D01*
X1231375Y291142D01*
X1239125D01*
G01X1212310Y400000D02*
Y412500D01*
X1206575Y403542D01*
X1214325D01*
G01X1220215Y401458D02*
X1221300Y400417D01*
X1222540Y400000D01*
X1223780Y400417D01*
X1224865Y401666D01*
X1225640Y403542D01*
X1225950Y405417D01*
Y407708D01*
X1225640Y409583D01*
X1224865Y411250D01*
X1223935Y412083D01*
X1222850Y412500D01*
X1221610Y412083D01*
X1220680Y411250D01*
X1220060Y410000D01*
X1219750Y408333D01*
X1220060Y406875D01*
X1220835Y405417D01*
X1221765Y404583D01*
X1222850Y404375D01*
X1224090Y404791D01*
X1225020Y405833D01*
X1225950Y407708D01*
G01X1232615Y401458D02*
X1233700Y400417D01*
X1234940Y400000D01*
X1236180Y400417D01*
X1237265Y401666D01*
X1238040Y403542D01*
X1238350Y405417D01*
Y407708D01*
X1238040Y409583D01*
X1237265Y411250D01*
X1236335Y412083D01*
X1235250Y412500D01*
X1234010Y412083D01*
X1233080Y411250D01*
X1232460Y410000D01*
X1232150Y408333D01*
X1232460Y406875D01*
X1233235Y405417D01*
X1234165Y404583D01*
X1235250Y404375D01*
X1236490Y404791D01*
X1237420Y405833D01*
X1238350Y407708D01*
G01X1204250Y371900D02*
Y384400D01*
X1202390Y381900D01*
G01Y371900D02*
X1206110D01*
G01X1213240Y373775D02*
X1214170Y372733D01*
X1215255Y372108D01*
X1216650Y371900D01*
X1218045Y372317D01*
X1219130Y373150D01*
X1219905Y374608D01*
X1220060Y376275D01*
X1219750Y377942D01*
X1218975Y378983D01*
X1217890Y379817D01*
X1216805Y380025D01*
X1215720Y379817D01*
X1214325Y378983D01*
X1214790Y384400D01*
X1218975D01*
G01X1228740Y371900D02*
X1229050Y374608D01*
X1229515Y376900D01*
X1230135Y378983D01*
X1230910Y381275D01*
X1232150Y384400D01*
X1225950D01*
G01X1241450Y371900D02*
X1242535Y372108D01*
X1243775Y372733D01*
X1244550Y373775D01*
X1244860Y375233D01*
X1244550Y376691D01*
X1243620Y377942D01*
X1242225Y378567D01*
X1240675D01*
X1239745Y378983D01*
X1238970Y380025D01*
X1238660Y381483D01*
X1239125Y382942D01*
X1240210Y383983D01*
X1241450Y384400D01*
X1242690Y383983D01*
X1243775Y382942D01*
X1244240Y381483D01*
X1243930Y380025D01*
X1243155Y378983D01*
X1242225Y378567D01*
X1240675D01*
X1239280Y377942D01*
X1238350Y376691D01*
X1238040Y375233D01*
X1238350Y373775D01*
X1239125Y372733D01*
X1240365Y372108D01*
X1241450Y371900D01*
G01X1210450Y429650D02*
X1209210Y429858D01*
X1208125Y430691D01*
X1207195Y431942D01*
X1206575Y433400D01*
X1206265Y435067D01*
Y436733D01*
X1206575Y438400D01*
X1207195Y439858D01*
X1208125Y441108D01*
X1209210Y441942D01*
X1210450Y442150D01*
X1211690Y441942D01*
X1212775Y441108D01*
X1213705Y439858D01*
X1214325Y438400D01*
X1214635Y436733D01*
Y435067D01*
X1214325Y433400D01*
X1213705Y431942D01*
X1212775Y430691D01*
X1211690Y429858D01*
X1210450Y429650D01*
G01X1211690Y432983D02*
X1213550Y429650D01*
G01X1222850Y442150D02*
Y429650D01*
G01X1219285Y442150D02*
X1226415D01*
G01X1235250Y429650D02*
Y435275D01*
X1232150Y442150D01*
G01X1238350D02*
X1235250Y435275D01*
G01X1224710Y90900D02*
Y103400D01*
X1218975Y94442D01*
X1226725D01*
G01X1216650Y62800D02*
Y75300D01*
X1214790Y72800D01*
G01Y62800D02*
X1218510D01*
G01X1226105Y73217D02*
X1227035Y74466D01*
X1228120Y75092D01*
X1229360Y75300D01*
X1230910Y74883D01*
X1231995Y73842D01*
X1232305Y72592D01*
X1232150Y71341D01*
X1231530Y70300D01*
X1228430Y68217D01*
X1227035Y66758D01*
X1226105Y64675D01*
X1225795Y62800D01*
X1232305D01*
G01X1224710Y119000D02*
Y131500D01*
X1218975Y122542D01*
X1226725D01*
G01X1224710Y175200D02*
Y187700D01*
X1218975Y178742D01*
X1226725D01*
G01X1219905Y152308D02*
X1220990Y153767D01*
X1221920Y154600D01*
X1223160Y155017D01*
X1224245Y154600D01*
X1225020Y153767D01*
X1225640Y152517D01*
X1225795Y151058D01*
X1225640Y149808D01*
X1225020Y148558D01*
X1224090Y147517D01*
X1223005Y147100D01*
X1221765Y147517D01*
X1220680Y148766D01*
X1220060Y150642D01*
X1219905Y152725D01*
X1220215Y155433D01*
X1220680Y156892D01*
X1221455Y158350D01*
X1222540Y159392D01*
X1223625Y159600D01*
X1224710Y159183D01*
X1225485Y158142D01*
G01X1219905Y241817D02*
X1220835Y243066D01*
X1221920Y243692D01*
X1223160Y243900D01*
X1224710Y243483D01*
X1225795Y242442D01*
X1226105Y241192D01*
X1225950Y239941D01*
X1225330Y238900D01*
X1222230Y236817D01*
X1220835Y235358D01*
X1219905Y233275D01*
X1219595Y231400D01*
X1226105D01*
G01X1219440Y205175D02*
X1220370Y204133D01*
X1221455Y203508D01*
X1222850Y203300D01*
X1224245Y203717D01*
X1225330Y204550D01*
X1226105Y206008D01*
X1226260Y207675D01*
X1225950Y209342D01*
X1225175Y210383D01*
X1224090Y211217D01*
X1223005Y211425D01*
X1221920Y211217D01*
X1220525Y210383D01*
X1220990Y215800D01*
X1225175D01*
G01X1219905Y264708D02*
X1220990Y266167D01*
X1221920Y267000D01*
X1223160Y267417D01*
X1224245Y267000D01*
X1225020Y266167D01*
X1225640Y264917D01*
X1225795Y263458D01*
X1225640Y262208D01*
X1225020Y260958D01*
X1224090Y259917D01*
X1223005Y259500D01*
X1221765Y259917D01*
X1220680Y261166D01*
X1220060Y263042D01*
X1219905Y265125D01*
X1220215Y267833D01*
X1220680Y269292D01*
X1221455Y270750D01*
X1222540Y271792D01*
X1223625Y272000D01*
X1224710Y271583D01*
X1225485Y270542D01*
G01X1216650Y343800D02*
Y356300D01*
X1214790Y353800D01*
G01Y343800D02*
X1218510D01*
G01X1229050D02*
X1230135Y344008D01*
X1231375Y344633D01*
X1232150Y345675D01*
X1232460Y347133D01*
X1232150Y348591D01*
X1231220Y349842D01*
X1229825Y350467D01*
X1228275D01*
X1227345Y350883D01*
X1226570Y351925D01*
X1226260Y353383D01*
X1226725Y354842D01*
X1227810Y355883D01*
X1229050Y356300D01*
X1230290Y355883D01*
X1231375Y354842D01*
X1231840Y353383D01*
X1231530Y351925D01*
X1230755Y350883D01*
X1229825Y350467D01*
X1228275D01*
X1226880Y349842D01*
X1225950Y348591D01*
X1225640Y347133D01*
X1225950Y345675D01*
X1226725Y344633D01*
X1227965Y344008D01*
X1229050Y343800D01*
G01X1213240Y318200D02*
X1214170Y316741D01*
X1215410Y315908D01*
X1216805Y315700D01*
X1218045Y315908D01*
X1219285Y316950D01*
X1220060Y318200D01*
X1220215Y319450D01*
X1219905Y320908D01*
X1218820Y321950D01*
X1217735Y322367D01*
X1216340D01*
G01X1217735D02*
X1218665Y322992D01*
X1219440Y324033D01*
X1219750Y325283D01*
X1219440Y326533D01*
X1218665Y327575D01*
X1217270Y328200D01*
X1215875Y327992D01*
X1214480Y327158D01*
G01X1226105Y320908D02*
X1227190Y322367D01*
X1228120Y323200D01*
X1229360Y323617D01*
X1230445Y323200D01*
X1231220Y322367D01*
X1231840Y321117D01*
X1231995Y319658D01*
X1231840Y318408D01*
X1231220Y317158D01*
X1230290Y316117D01*
X1229205Y315700D01*
X1227965Y316117D01*
X1226880Y317366D01*
X1226260Y319242D01*
X1226105Y321325D01*
X1226415Y324033D01*
X1226880Y325492D01*
X1227655Y326950D01*
X1228740Y327992D01*
X1229825Y328200D01*
X1230910Y327783D01*
X1231685Y326742D01*
G54D15*
X32425Y177900D03*
X26450Y274750D03*
X34200Y284800D03*
X32600Y290500D03*
X25500Y321200D03*
X21600Y333800D03*
X29500Y343500D03*
X23100Y342400D03*
X32675Y299500D03*
X23400Y353500D03*
X34000Y448000D03*
X29500Y410500D03*
X33200Y468900D03*
X14000Y476000D03*
X28800Y533700D03*
X5304Y548800D03*
Y528900D03*
X33450Y574300D03*
X5094Y574500D03*
X29500Y586500D03*
X23450Y577491D03*
X25148Y570800D03*
X27000Y573800D03*
X4594Y749000D03*
Y714000D03*
X5000Y1355000D03*
X26700Y1529800D03*
X28000Y1596800D03*
X13300Y1644300D03*
X10500Y1648800D03*
X35500Y1670500D03*
X31400Y1648200D03*
X13300Y1689600D03*
X19542Y1710518D03*
X29100Y1721550D03*
X34000Y1691500D03*
X19200Y1707000D03*
X25000Y1763800D03*
X22000Y1787800D03*
X27400Y1899400D03*
X64000Y67553D03*
X64500Y53000D03*
X70454Y60031D03*
X74000Y60500D03*
X79000Y65500D03*
X75000Y67500D03*
X84500Y56500D03*
X81500Y75500D03*
X63500Y63500D03*
X59600Y125800D03*
X75300Y155300D03*
X49924Y153261D03*
X53000Y171500D03*
X65000Y166300D03*
X60350Y151950D03*
X39300Y181100D03*
X63500Y179300D03*
X53400Y191300D03*
X39300Y175500D03*
X43700Y181200D03*
X43400Y174325D03*
X52700Y162300D03*
X64400Y183400D03*
X52500Y175200D03*
X70500Y190200D03*
X54400Y217000D03*
X65200Y207850D03*
X57424Y232974D03*
X42720Y233990D03*
X65000Y241500D03*
Y235400D03*
X54200Y207850D03*
Y220700D03*
X51700Y234800D03*
X41100Y231000D03*
X71400Y208150D03*
X69900Y236600D03*
X77900Y229034D03*
X70600Y217600D03*
X74800Y231800D03*
X69400Y226100D03*
X61300Y229400D03*
X38000Y228500D03*
X75300Y211300D03*
X85676Y231100D03*
X72100Y221700D03*
X49700Y209700D03*
X53500Y199700D03*
X47800Y199200D03*
X64000Y199700D03*
X60300Y275700D03*
X57500Y268500D03*
X68000Y268000D03*
X70600Y250500D03*
X42500Y254100D03*
X48500Y248600D03*
X42500Y260200D03*
X36000Y260386D03*
X58936Y256289D03*
X52500Y248500D03*
X50800Y266400D03*
X54000Y275600D03*
X45800Y277800D03*
X43400Y272300D03*
X78000Y429500D03*
X52100Y513100D03*
X46500Y511000D03*
X46000Y516000D03*
X51000Y529500D03*
X66000Y550500D03*
X71445Y532192D03*
X72397Y528297D03*
X77800Y540300D03*
X63400Y581400D03*
X49700Y568900D03*
X65000Y561500D03*
X78400Y583700D03*
X70350Y558850D03*
X54600Y573400D03*
X82000Y652000D03*
X66200Y653500D03*
X84200Y643865D03*
X75571Y692496D03*
X53000Y673500D03*
X57684Y697639D03*
X64000Y666600D03*
X52500Y682500D03*
X78494Y697835D03*
X53000Y695100D03*
X39800Y681400D03*
X86597Y681103D03*
X43388Y694286D03*
X49500Y703500D03*
X46500Y705500D03*
X44500Y697500D03*
X60900Y670200D03*
X60500Y682540D03*
X76100Y686900D03*
X83850Y678109D03*
X73000Y728000D03*
X69000Y726800D03*
X71500Y735500D03*
X73500Y732000D03*
X86500Y723500D03*
X57500Y844500D03*
X72400Y822900D03*
X51200Y827000D03*
X61207Y828350D03*
X49600Y889400D03*
X55700Y880000D03*
X59500Y881600D03*
X57500Y890300D03*
X56000Y885500D03*
X64600Y882700D03*
X61600Y885200D03*
X67200Y888800D03*
X54300Y915500D03*
X54000Y996500D03*
X70800Y990500D03*
X57500Y987800D03*
Y984300D03*
X83500Y976300D03*
Y972800D03*
X83000Y979800D03*
X53800Y1006200D03*
X53500Y1025500D03*
X56000Y1021500D03*
X54500Y1035500D03*
X51000Y1018000D03*
X82094Y1112500D03*
X64500Y1099000D03*
X37500Y1099823D03*
X70500Y1161500D03*
X73163Y1158780D03*
X71100Y1171000D03*
X68800Y1178800D03*
X39400Y1381300D03*
X44500Y1380500D03*
X45500Y1400000D03*
X80000Y1472000D03*
X83200Y1455500D03*
X45000Y1428000D03*
X36400Y1523400D03*
X67700Y1568700D03*
X43500Y1620700D03*
X42700Y1606000D03*
X38400Y1596700D03*
X83000Y1619703D03*
X83050Y1616000D03*
X42500Y1673000D03*
X44500Y1678000D03*
X43600Y1668300D03*
X43300Y1646600D03*
X45500Y1690000D03*
X41500Y1692000D03*
X40300Y1703900D03*
X44100Y1685200D03*
X45300Y1776300D03*
X52500Y1756000D03*
X55900Y1881500D03*
X62000Y1877000D03*
X57900Y1899800D03*
X65300Y1886600D03*
X38700Y1893800D03*
X41500Y1889500D03*
X60300Y1892300D03*
X47000Y1886200D03*
X79900Y1923000D03*
X109500Y62000D03*
X89500Y49500D03*
X99500Y61000D03*
X115000Y76500D03*
X109000D03*
X98500Y73000D03*
X115500Y59500D03*
X97000Y51500D03*
X91500Y88500D03*
Y92500D03*
X92500Y73000D03*
X88253Y65500D03*
X112000Y101000D03*
X104500D03*
X91000Y97000D03*
X93000Y107000D03*
X93900Y111800D03*
X93500Y101500D03*
X117600Y234900D03*
X122100Y230100D03*
X127200Y246000D03*
X122500Y441000D03*
X135500D03*
X108100Y477650D03*
X91300Y528200D03*
X108900Y541300D03*
X102700Y541000D03*
X106300Y553200D03*
X110400Y550800D03*
X87700Y528000D03*
X132500Y539621D03*
X115300Y551800D03*
X129000Y597000D03*
X124200Y568400D03*
X119800Y568300D03*
X133500Y575500D03*
X137000Y589900D03*
X133500Y582000D03*
X134600Y586700D03*
X88000Y586500D03*
X101000Y583000D03*
X96000Y588000D03*
X89000Y595000D03*
X87000Y591000D03*
X135000Y561500D03*
X121000Y581500D03*
X124900Y582000D03*
X91300Y577000D03*
X92200Y553800D03*
X116000Y596900D03*
X113655Y599363D03*
X128900Y580500D03*
X122300Y575000D03*
X131135Y639554D03*
X87000Y648000D03*
X122500Y653650D03*
X117400Y653100D03*
X91250Y704700D03*
X134600Y665600D03*
X130000Y700500D03*
X122500D03*
X114500D03*
X105500Y702500D03*
X93000Y698500D03*
X88500Y700000D03*
X98000Y698500D03*
Y703000D03*
X100200Y663900D03*
X118127Y663400D03*
X109005Y665890D03*
X114000Y663350D03*
X130000Y753000D03*
Y746000D03*
X119500Y757500D03*
Y746500D03*
Y739500D03*
X113500Y729000D03*
Y736000D03*
Y747000D03*
Y756000D03*
Y721000D03*
X106000Y709000D03*
X98000Y708000D03*
X130000Y764000D03*
X118700Y840700D03*
X98900Y822900D03*
X114900Y824100D03*
X106404Y840700D03*
X100300Y841000D03*
X111500Y851600D03*
X101500Y874200D03*
X102300Y863438D03*
X107164Y862285D03*
X113400Y862200D03*
X125400Y983600D03*
Y992000D03*
X97300Y990800D03*
X94000Y971800D03*
X104000Y1062500D03*
Y1049500D03*
X127200Y1015200D03*
X105000Y1181000D03*
X119500Y1261000D03*
X119000Y1255968D03*
X128700Y1408000D03*
X135601Y1416200D03*
X134500Y1420000D03*
X125000Y1398500D03*
X100860Y1402260D03*
X111000Y1394000D03*
X125100Y1402500D03*
X131174Y1412700D03*
X89000Y1428171D03*
X110000Y1429500D03*
X132000Y1436500D03*
X112750Y1491250D03*
X121000Y1506500D03*
X113000D03*
X117000D03*
X109000D03*
X133000Y1505500D03*
X128999Y1506499D03*
X125000Y1506500D03*
X135008Y1508245D03*
X132300Y1491100D03*
X108500Y1569000D03*
X113200Y1622800D03*
Y1619300D03*
X91100Y1922800D03*
X128900Y1923300D03*
X104600Y1923400D03*
X133500Y1906500D03*
X149500Y52000D03*
X146960Y432400D03*
X142000Y478500D03*
X165300Y481100D03*
X144000Y509500D03*
X166100Y527900D03*
X147000Y529900D03*
X156300Y552100D03*
X142500Y550000D03*
X162500Y527900D03*
X159850Y541800D03*
X182588Y542288D03*
X154600Y581500D03*
X159250Y590250D03*
X145800Y594400D03*
X142100Y581400D03*
X160000Y562500D03*
X147900Y588100D03*
X138900Y650100D03*
X139200Y653900D03*
X174196Y628196D03*
X150978Y687775D03*
X142648Y665429D03*
X165433Y692372D03*
X161000Y674000D03*
X157500Y664500D03*
X147000Y703000D03*
X149000Y677000D03*
X155200Y679500D03*
X161500Y691700D03*
X150700D03*
X153192Y705890D03*
X146000Y755000D03*
X166000Y751500D03*
X170000Y745500D03*
X161600Y739800D03*
X161500Y747500D03*
X146000Y726000D03*
X165900Y717300D03*
X146000Y738000D03*
X175100Y710000D03*
X158600Y752600D03*
X146000Y765500D03*
Y796500D03*
Y782500D03*
X166000Y760000D03*
X166500Y775500D03*
X161500Y759000D03*
Y768000D03*
Y778000D03*
X146500Y812000D03*
X146000Y824000D03*
X180000Y856000D03*
X162000Y817500D03*
X174000Y834500D03*
X168000Y830000D03*
X180000Y872500D03*
X179500Y884000D03*
X179900Y900900D03*
X157800Y898000D03*
X147500Y900500D03*
X180000Y960400D03*
X179900Y925700D03*
X179800Y941400D03*
X180000Y912500D03*
X143000Y953032D03*
X146500Y953030D03*
X149772Y954121D03*
X152747Y952474D03*
X163100Y978600D03*
X163200Y985200D03*
X149800Y1008700D03*
X179000Y1005000D03*
X180500Y973200D03*
X150500Y976500D03*
X155000Y974500D03*
X155500Y1030000D03*
X153500Y1033500D03*
X151500Y1030500D03*
X159500Y1062000D03*
X163000Y1042500D03*
X146500Y1397100D03*
X155900D03*
X139900Y1415100D03*
X142500Y1420500D03*
X169000Y1426750D03*
X158500Y1466500D03*
X151500Y1438500D03*
X157500Y1454800D03*
X142000Y1494800D03*
X147500Y1498000D03*
X153500Y1496500D03*
X143518Y1567520D03*
X177500Y1569500D03*
X141300Y1625000D03*
X169876Y1626303D03*
X141500Y1621600D03*
X173270Y1626517D03*
X152500Y1883100D03*
X184500Y1920500D03*
X170000D03*
X162100Y1912000D03*
X151900Y1891400D03*
X146300Y1913700D03*
X142400Y1923800D03*
X176700Y1923900D03*
X177700Y1912800D03*
X157900Y1923100D03*
X201500Y165000D03*
X191400Y432405D03*
X202210Y638500D03*
X201500Y691500D03*
X202500Y666000D03*
X201500Y726500D03*
X202500Y755500D03*
X201500Y777000D03*
X201389Y797000D03*
X202000Y859500D03*
X202500Y822000D03*
Y846500D03*
X202000Y890000D03*
X202210Y903500D03*
X202000Y875000D03*
X202500Y945500D03*
X202000Y918000D03*
X202500Y962000D03*
X201500Y931500D03*
X202500Y1006000D03*
Y977500D03*
X201500Y991000D03*
X202000Y1037000D03*
Y1052000D03*
X201500Y1019000D03*
X201389Y1067000D03*
X201500Y1082500D03*
X195000Y1112000D03*
X201500Y1147000D03*
X202000Y1212000D03*
X202500Y1179000D03*
X202000Y1246000D03*
X201500Y1306500D03*
X202500Y1280000D03*
X201500Y1359500D03*
Y1350000D03*
X201700Y1388300D03*
X201500Y1413000D03*
X202400Y1444000D03*
X201389Y1425500D03*
X202210Y1462000D03*
X194500Y1510000D03*
Y1505500D03*
X196500Y1572000D03*
Y1606500D03*
X192500Y1653000D03*
Y1648000D03*
X192650Y1641500D03*
X200500Y1876500D03*
X201200Y1890500D03*
X201100Y1908800D03*
X822950Y406250D03*
G54D16*
X31299Y230866D03*
Y220866D03*
Y210866D03*
Y348563D03*
Y338563D03*
Y358563D03*
Y903917D03*
Y923917D03*
Y913917D03*
Y1064587D03*
Y1054587D03*
Y1044587D03*
Y1619941D03*
Y1609941D03*
Y1629941D03*
Y1757638D03*
Y1747638D03*
Y1737638D03*
X822950Y350050D03*
G54D17*
X27559Y629921D03*
X17716Y1338583D03*
X27559Y1811023D03*
X179134Y78740D03*
X179133Y570866D03*
X179134Y1161417D03*
X822950Y265750D03*
G54D18*
X47244Y68110D03*
Y501338D03*
Y761181D03*
Y1207323D03*
Y1467165D03*
Y1900393D03*
X822950Y153350D03*
G54D19*
X80709Y119409D03*
Y329409D03*
X149606Y119409D03*
Y329409D03*
X822950Y125250D03*
M02*
